FILE_TYPE = MACRO_DRAWING;
SET COLOR_WIRE YELLOW;
SET COLOR_PROP ORANGE;
SET COLOR_DOT WHITE;
SET COLOR_ARC YELLOW;
SET COLOR_BODY GREEN;
SET COLOR_NOTE PURPLE;
SET PROP_DISPLAY VALUE;
SET PAGE_NUMBER P27;
SET PATH_NUMBER P247;
FORCEADD Q_RES..1
(-3625 2975);
FORCEPROP 1 LAST MATERIAL CHIP
J 0
(-3500 2975);
DISPLAY 0.510638 (-3500 2975);
PAINT SKYBLUE (-3500 2975);
FORCEPROP 1 LAST VALUE 2.2K
J 2
(-3750 2975);
DISPLAY 0.510638 (-3750 2975);
PAINT SKYBLUE (-3750 2975);
FORCEPROP 1 LAST TOLERANCE 5%
J 0
(-3625 2875);
DISPLAY 0.510638 (-3625 2875);
PAINT SKYBLUE (-3625 2875);
DISPLAY INVISIBLE (-3625 2875);
FORCEPROP 1 LAST PART_NUMBER CS22202JB07
J 0
(-3675 3075);
DISPLAY 0.510638 (-3675 3075);
PAINT WHITE (-3675 3075);
DISPLAY INVISIBLE (-3675 3075);
FORCEPROP 1 LAST PACK_TYPE 0402LF
J 0
(-3375 2825);
DISPLAY 0.510638 (-3375 2825);
PAINT SKYBLUE (-3375 2825);
DISPLAY INVISIBLE (-3375 2825);
FORCEPROP 1 LAST WATTAGE 1/16W
J 2
(-3650 2825);
DISPLAY 0.510638 (-3650 2825);
PAINT SKYBLUE (-3650 2825);
DISPLAY INVISIBLE (-3650 2825);
FORCEPROP 1 LAST PATH I100
J 0
(-3675 3125);
DISPLAY 0.978723 (-3675 3125);
PAINT WHITE (-3675 3125);
DISPLAY INVISIBLE (-3675 3125);
FORCEPROP 2 LAST CDS_LIB pure_quanta
J 0
(-3625 2975);
DISPLAY INVISIBLE (-3625 2975);
FORCEPROP 1 LAST LOCATION R256
J 0
(-3975 2975);
DISPLAY 0.702128 (-3975 2975);
PAINT YELLOW (-3975 2975);
FORCEPROP 0 LAST $SEC 1
J 0
(-3900 3025);
DISPLAY INVISIBLE (-3900 3025);
FORCEPROP 0 LAST CDS_SEC 1
J 0
(-3900 3025);
DISPLAY INVISIBLE (-3900 3025);
FORCEPROP 1 LASTPIN (-3725 2975) $PN 1
J 0
(-3713 2987);
DISPLAY 0.808511 (-3713 2987);
PAINT WHITE (-3713 2987);
DISPLAY INVISIBLE (-3713 2987);
FORCEPROP 1 LASTPIN (-3525 2975) $PN 2
J 0
(-3563 2987);
DISPLAY 0.808511 (-3563 2987);
PAINT WHITE (-3563 2987);
DISPLAY INVISIBLE (-3563 2987);
FORCEADD Q_RES..1
(-3625 3175);
FORCEPROP 1 LAST MATERIAL CHIP
J 0
(-3500 3175);
DISPLAY 0.510638 (-3500 3175);
PAINT SKYBLUE (-3500 3175);
FORCEPROP 1 LAST VALUE 10K
J 2
(-3750 3175);
DISPLAY 0.510638 (-3750 3175);
PAINT SKYBLUE (-3750 3175);
FORCEPROP 1 LAST PART_NUMBER CS31002FB08
J 0
(-3675 3275);
DISPLAY 0.510638 (-3675 3275);
PAINT WHITE (-3675 3275);
DISPLAY INVISIBLE (-3675 3275);
FORCEPROP 1 LAST TOLERANCE 1%
J 0
(-3625 3075);
DISPLAY 0.510638 (-3625 3075);
PAINT SKYBLUE (-3625 3075);
DISPLAY INVISIBLE (-3625 3075);
FORCEPROP 2 LAST CDS_LIB pure_quanta
J 0
(-3625 3175);
DISPLAY INVISIBLE (-3625 3175);
FORCEPROP 1 LAST PATH I101
J 0
(-3675 3325);
DISPLAY 0.978723 (-3675 3325);
PAINT WHITE (-3675 3325);
DISPLAY INVISIBLE (-3675 3325);
FORCEPROP 1 LAST WATTAGE 1/16W
J 2
(-3650 3025);
DISPLAY 0.510638 (-3650 3025);
PAINT SKYBLUE (-3650 3025);
DISPLAY INVISIBLE (-3650 3025);
FORCEPROP 1 LAST PACK_TYPE 0402LF
J 0
(-3375 3025);
DISPLAY 0.510638 (-3375 3025);
PAINT SKYBLUE (-3375 3025);
DISPLAY INVISIBLE (-3375 3025);
FORCEPROP 1 LAST LOCATION R254
J 0
(-3975 3175);
DISPLAY 0.702128 (-3975 3175);
PAINT YELLOW (-3975 3175);
FORCEPROP 0 LAST $SEC 1
J 0
(-3900 3225);
DISPLAY INVISIBLE (-3900 3225);
FORCEPROP 0 LAST CDS_SEC 1
J 0
(-3900 3225);
DISPLAY INVISIBLE (-3900 3225);
FORCEPROP 1 LASTPIN (-3725 3175) $PN 1
J 0
(-3713 3187);
DISPLAY 0.808511 (-3713 3187);
PAINT WHITE (-3713 3187);
DISPLAY INVISIBLE (-3713 3187);
FORCEPROP 1 LASTPIN (-3525 3175) $PN 2
J 0
(-3563 3187);
DISPLAY 0.808511 (-3563 3187);
PAINT WHITE (-3563 3187);
DISPLAY INVISIBLE (-3563 3187);
FORCEADD Q_RES..1
(-3625 3075);
FORCEPROP 1 LAST VALUE 10K
J 2
(-3750 3075);
DISPLAY 0.510638 (-3750 3075);
PAINT SKYBLUE (-3750 3075);
FORCEPROP 1 LAST MATERIAL CHIP
J 0
(-3500 3075);
DISPLAY 0.510638 (-3500 3075);
PAINT SKYBLUE (-3500 3075);
FORCEPROP 1 LAST PART_NUMBER CS31002FB08
J 0
(-3675 3175);
DISPLAY 0.510638 (-3675 3175);
PAINT WHITE (-3675 3175);
DISPLAY INVISIBLE (-3675 3175);
FORCEPROP 1 LAST TOLERANCE 1%
J 0
(-3625 2975);
DISPLAY 0.510638 (-3625 2975);
PAINT SKYBLUE (-3625 2975);
DISPLAY INVISIBLE (-3625 2975);
FORCEPROP 2 LAST CDS_LIB pure_quanta
J 0
(-3625 3075);
DISPLAY INVISIBLE (-3625 3075);
FORCEPROP 1 LAST PATH I102
J 0
(-3675 3225);
DISPLAY 0.978723 (-3675 3225);
PAINT WHITE (-3675 3225);
DISPLAY INVISIBLE (-3675 3225);
FORCEPROP 1 LAST WATTAGE 1/16W
J 2
(-3650 2925);
DISPLAY 0.510638 (-3650 2925);
PAINT SKYBLUE (-3650 2925);
DISPLAY INVISIBLE (-3650 2925);
FORCEPROP 1 LAST PACK_TYPE 0402LF
J 0
(-3375 2925);
DISPLAY 0.510638 (-3375 2925);
PAINT SKYBLUE (-3375 2925);
DISPLAY INVISIBLE (-3375 2925);
FORCEPROP 1 LAST LOCATION R255
J 0
(-3975 3075);
DISPLAY 0.702128 (-3975 3075);
PAINT YELLOW (-3975 3075);
FORCEPROP 0 LAST $SEC 1
J 0
(-3900 3125);
DISPLAY INVISIBLE (-3900 3125);
FORCEPROP 0 LAST CDS_SEC 1
J 0
(-3900 3125);
DISPLAY INVISIBLE (-3900 3125);
FORCEPROP 1 LASTPIN (-3725 3075) $PN 1
J 0
(-3713 3087);
DISPLAY 0.808511 (-3713 3087);
PAINT WHITE (-3713 3087);
DISPLAY INVISIBLE (-3713 3087);
FORCEPROP 1 LASTPIN (-3525 3075) $PN 2
J 0
(-3563 3087);
DISPLAY 0.808511 (-3563 3087);
PAINT WHITE (-3563 3087);
DISPLAY INVISIBLE (-3563 3087);
FORCEADD Q_RES..1
(-3625 3275);
FORCEPROP 1 LAST MATERIAL CHIP
J 0
(-3500 3275);
DISPLAY 0.510638 (-3500 3275);
PAINT SKYBLUE (-3500 3275);
FORCEPROP 1 LAST VALUE 2.2K
J 2
(-3750 3275);
DISPLAY 0.510638 (-3750 3275);
PAINT SKYBLUE (-3750 3275);
FORCEPROP 1 LAST TOLERANCE 5%
J 0
(-3625 3175);
DISPLAY 0.510638 (-3625 3175);
PAINT SKYBLUE (-3625 3175);
DISPLAY INVISIBLE (-3625 3175);
FORCEPROP 1 LAST PART_NUMBER CS22202JB07
J 0
(-3675 3375);
DISPLAY 0.510638 (-3675 3375);
PAINT WHITE (-3675 3375);
DISPLAY INVISIBLE (-3675 3375);
FORCEPROP 1 LAST PACK_TYPE 0402LF
J 0
(-3375 3125);
DISPLAY 0.510638 (-3375 3125);
PAINT SKYBLUE (-3375 3125);
DISPLAY INVISIBLE (-3375 3125);
FORCEPROP 1 LAST WATTAGE 1/16W
J 2
(-3650 3125);
DISPLAY 0.510638 (-3650 3125);
PAINT SKYBLUE (-3650 3125);
DISPLAY INVISIBLE (-3650 3125);
FORCEPROP 1 LAST PATH I103
J 0
(-3675 3425);
DISPLAY 0.978723 (-3675 3425);
PAINT WHITE (-3675 3425);
DISPLAY INVISIBLE (-3675 3425);
FORCEPROP 2 LAST CDS_LIB pure_quanta
J 0
(-3625 3275);
DISPLAY INVISIBLE (-3625 3275);
FORCEPROP 1 LAST LOCATION R253
J 0
(-3975 3275);
DISPLAY 0.702128 (-3975 3275);
PAINT YELLOW (-3975 3275);
FORCEPROP 0 LAST $SEC 1
J 0
(-3900 3325);
DISPLAY INVISIBLE (-3900 3325);
FORCEPROP 0 LAST CDS_SEC 1
J 0
(-3900 3325);
DISPLAY INVISIBLE (-3900 3325);
FORCEPROP 1 LASTPIN (-3725 3275) $PN 1
J 0
(-3713 3287);
DISPLAY 0.808511 (-3713 3287);
PAINT WHITE (-3713 3287);
DISPLAY INVISIBLE (-3713 3287);
FORCEPROP 1 LASTPIN (-3525 3275) $PN 2
J 0
(-3563 3287);
DISPLAY 0.808511 (-3563 3287);
PAINT WHITE (-3563 3287);
DISPLAY INVISIBLE (-3563 3287);
FORCEADD Q_RES..1
(-3625 3375);
FORCEPROP 1 LAST MATERIAL CHIP
J 0
(-3500 3375);
DISPLAY 0.510638 (-3500 3375);
PAINT SKYBLUE (-3500 3375);
FORCEPROP 1 LAST VALUE 2.2K
J 2
(-3750 3375);
DISPLAY 0.510638 (-3750 3375);
PAINT SKYBLUE (-3750 3375);
FORCEPROP 1 LAST TOLERANCE 5%
J 0
(-3625 3275);
DISPLAY 0.510638 (-3625 3275);
PAINT SKYBLUE (-3625 3275);
DISPLAY INVISIBLE (-3625 3275);
FORCEPROP 1 LAST PART_NUMBER CS22202JB07
J 0
(-3675 3475);
DISPLAY 0.510638 (-3675 3475);
PAINT WHITE (-3675 3475);
DISPLAY INVISIBLE (-3675 3475);
FORCEPROP 1 LAST PACK_TYPE 0402LF
J 0
(-3375 3225);
DISPLAY 0.510638 (-3375 3225);
PAINT SKYBLUE (-3375 3225);
DISPLAY INVISIBLE (-3375 3225);
FORCEPROP 1 LAST WATTAGE 1/16W
J 2
(-3650 3225);
DISPLAY 0.510638 (-3650 3225);
PAINT SKYBLUE (-3650 3225);
DISPLAY INVISIBLE (-3650 3225);
FORCEPROP 1 LAST PATH I105
J 0
(-3675 3525);
DISPLAY 0.978723 (-3675 3525);
PAINT WHITE (-3675 3525);
DISPLAY INVISIBLE (-3675 3525);
FORCEPROP 2 LAST CDS_LIB pure_quanta
J 0
(-3625 3375);
DISPLAY INVISIBLE (-3625 3375);
FORCEPROP 1 LAST LOCATION R252
J 0
(-3975 3375);
DISPLAY 0.702128 (-3975 3375);
PAINT YELLOW (-3975 3375);
FORCEPROP 0 LAST $SEC 1
J 0
(-3900 3425);
DISPLAY INVISIBLE (-3900 3425);
FORCEPROP 0 LAST CDS_SEC 1
J 0
(-3900 3425);
DISPLAY INVISIBLE (-3900 3425);
FORCEPROP 1 LASTPIN (-3725 3375) $PN 1
J 0
(-3713 3387);
DISPLAY 0.808511 (-3713 3387);
PAINT WHITE (-3713 3387);
DISPLAY INVISIBLE (-3713 3387);
FORCEPROP 1 LASTPIN (-3525 3375) $PN 2
J 0
(-3563 3387);
DISPLAY 0.808511 (-3563 3387);
PAINT WHITE (-3563 3387);
DISPLAY INVISIBLE (-3563 3387);
FORCEADD Q_RES..1
(-3625 3575);
FORCEPROP 1 LAST MATERIAL CHIP
J 0
(-3500 3575);
DISPLAY 0.510638 (-3500 3575);
PAINT SKYBLUE (-3500 3575);
FORCEPROP 1 LAST VALUE 402
J 2
(-3775 3575);
DISPLAY 0.510638 (-3775 3575);
PAINT SKYBLUE (-3775 3575);
FORCEPROP 1 LAST WATTAGE 1/16W
J 2
(-3550 3525);
DISPLAY 0.638298 (-3550 3525);
DISPLAY INVISIBLE (-3550 3525);
FORCEPROP 1 LAST PACK_TYPE 0402LF
J 0
(-3375 3425);
DISPLAY 0.978723 (-3375 3425);
DISPLAY INVISIBLE (-3375 3425);
FORCEPROP 1 LAST TOLERANCE 1%
J 0
(-3625 3475);
DISPLAY 0.978723 (-3625 3475);
DISPLAY INVISIBLE (-3625 3475);
FORCEPROP 2 LAST CDS_LIB pure_quanta
J 0
(-3625 3575);
DISPLAY INVISIBLE (-3625 3575);
FORCEPROP 1 LAST PATH I106
J 0
(-3675 3725);
DISPLAY 0.978723 (-3675 3725);
PAINT WHITE (-3675 3725);
DISPLAY INVISIBLE (-3675 3725);
FORCEPROP 1 LAST PART_NUMBER CS14022FB02
J 0
(-3675 3675);
DISPLAY 0.787234 (-3675 3675);
DISPLAY INVISIBLE (-3675 3675);
FORCEPROP 1 LAST LOCATION R250
J 0
(-3975 3575);
DISPLAY 0.638298 (-3975 3575);
PAINT YELLOW (-3975 3575);
FORCEPROP 0 LAST $SEC 1
J 0
(-3975 3625);
DISPLAY 0.680851 (-3975 3625);
PAINT MONO (-3975 3625);
DISPLAY INVISIBLE (-3975 3625);
FORCEPROP 0 LAST CDS_SEC 1
J 0
(-3900 3625);
DISPLAY INVISIBLE (-3900 3625);
FORCEPROP 1 LASTPIN (-3725 3575) $PN 1
J 0
(-3713 3587);
DISPLAY 0.787234 (-3713 3587);
PAINT MONO (-3713 3587);
DISPLAY INVISIBLE (-3713 3587);
FORCEPROP 1 LASTPIN (-3525 3575) $PN 2
J 0
(-3563 3587);
DISPLAY 0.787234 (-3563 3587);
PAINT MONO (-3563 3587);
DISPLAY INVISIBLE (-3563 3587);
FORCEADD Q_RES..1
(-3625 3775);
FORCEPROP 1 LAST VALUE 2.2K
J 2
(-3750 3775);
DISPLAY 0.510638 (-3750 3775);
PAINT SKYBLUE (-3750 3775);
FORCEPROP 1 LAST MATERIAL CHIP
J 0
(-3500 3775);
DISPLAY 0.510638 (-3500 3775);
PAINT SKYBLUE (-3500 3775);
FORCEPROP 1 LAST TOLERANCE 5%
J 0
(-3625 3675);
DISPLAY 0.510638 (-3625 3675);
PAINT SKYBLUE (-3625 3675);
DISPLAY INVISIBLE (-3625 3675);
FORCEPROP 1 LAST PART_NUMBER CS22202JB07
J 0
(-3675 3875);
DISPLAY 0.510638 (-3675 3875);
PAINT WHITE (-3675 3875);
DISPLAY INVISIBLE (-3675 3875);
FORCEPROP 1 LAST PACK_TYPE 0402LF
J 0
(-3375 3625);
DISPLAY 0.510638 (-3375 3625);
PAINT SKYBLUE (-3375 3625);
DISPLAY INVISIBLE (-3375 3625);
FORCEPROP 1 LAST WATTAGE 1/16W
J 2
(-3650 3625);
DISPLAY 0.510638 (-3650 3625);
PAINT SKYBLUE (-3650 3625);
DISPLAY INVISIBLE (-3650 3625);
FORCEPROP 1 LAST PATH I107
J 0
(-3675 3925);
DISPLAY 0.978723 (-3675 3925);
PAINT WHITE (-3675 3925);
DISPLAY INVISIBLE (-3675 3925);
FORCEPROP 2 LAST CDS_LIB pure_quanta
J 0
(-3625 3775);
DISPLAY INVISIBLE (-3625 3775);
FORCEPROP 1 LAST LOCATION R248
J 0
(-3975 3775);
DISPLAY 0.702128 (-3975 3775);
PAINT YELLOW (-3975 3775);
FORCEPROP 0 LAST $SEC 1
J 0
(-3900 3825);
DISPLAY INVISIBLE (-3900 3825);
FORCEPROP 0 LAST CDS_SEC 1
J 0
(-3900 3825);
DISPLAY INVISIBLE (-3900 3825);
FORCEPROP 1 LASTPIN (-3725 3775) $PN 1
J 0
(-3713 3787);
DISPLAY 0.808511 (-3713 3787);
PAINT WHITE (-3713 3787);
DISPLAY INVISIBLE (-3713 3787);
FORCEPROP 1 LASTPIN (-3525 3775) $PN 2
J 0
(-3563 3787);
DISPLAY 0.808511 (-3563 3787);
PAINT WHITE (-3563 3787);
DISPLAY INVISIBLE (-3563 3787);
FORCEADD Q_RES..1
(-3625 3675);
FORCEPROP 1 LAST VALUE 2.2K
J 2
(-3750 3675);
DISPLAY 0.510638 (-3750 3675);
PAINT SKYBLUE (-3750 3675);
FORCEPROP 1 LAST MATERIAL CHIP
J 0
(-3500 3675);
DISPLAY 0.510638 (-3500 3675);
PAINT SKYBLUE (-3500 3675);
FORCEPROP 1 LAST TOLERANCE 5%
J 0
(-3625 3575);
DISPLAY 0.510638 (-3625 3575);
PAINT SKYBLUE (-3625 3575);
DISPLAY INVISIBLE (-3625 3575);
FORCEPROP 1 LAST PART_NUMBER CS22202JB07
J 0
(-3675 3775);
DISPLAY 0.510638 (-3675 3775);
PAINT WHITE (-3675 3775);
DISPLAY INVISIBLE (-3675 3775);
FORCEPROP 1 LAST PACK_TYPE 0402LF
J 0
(-3375 3525);
DISPLAY 0.510638 (-3375 3525);
PAINT SKYBLUE (-3375 3525);
DISPLAY INVISIBLE (-3375 3525);
FORCEPROP 1 LAST WATTAGE 1/16W
J 2
(-3650 3525);
DISPLAY 0.510638 (-3650 3525);
PAINT SKYBLUE (-3650 3525);
DISPLAY INVISIBLE (-3650 3525);
FORCEPROP 1 LAST PATH I108
J 0
(-3675 3825);
DISPLAY 0.978723 (-3675 3825);
PAINT WHITE (-3675 3825);
DISPLAY INVISIBLE (-3675 3825);
FORCEPROP 2 LAST CDS_LIB pure_quanta
J 0
(-3625 3675);
DISPLAY INVISIBLE (-3625 3675);
FORCEPROP 1 LAST LOCATION R249
J 0
(-3975 3675);
DISPLAY 0.702128 (-3975 3675);
PAINT YELLOW (-3975 3675);
FORCEPROP 0 LAST $SEC 1
J 0
(-3900 3725);
DISPLAY INVISIBLE (-3900 3725);
FORCEPROP 0 LAST CDS_SEC 1
J 0
(-3900 3725);
DISPLAY INVISIBLE (-3900 3725);
FORCEPROP 1 LASTPIN (-3725 3675) $PN 1
J 0
(-3713 3687);
DISPLAY 0.808511 (-3713 3687);
PAINT WHITE (-3713 3687);
DISPLAY INVISIBLE (-3713 3687);
FORCEPROP 1 LASTPIN (-3525 3675) $PN 2
J 0
(-3563 3687);
DISPLAY 0.808511 (-3563 3687);
PAINT WHITE (-3563 3687);
DISPLAY INVISIBLE (-3563 3687);
FORCEADD Q_RES..1
(-3625 3875);
FORCEPROP 1 LAST VALUE 2.2K
J 2
(-3750 3875);
DISPLAY 0.510638 (-3750 3875);
PAINT SKYBLUE (-3750 3875);
FORCEPROP 1 LAST MATERIAL CHIP
J 0
(-3500 3875);
DISPLAY 0.510638 (-3500 3875);
PAINT SKYBLUE (-3500 3875);
FORCEPROP 1 LAST TOLERANCE 5%
J 0
(-3625 3775);
DISPLAY 0.510638 (-3625 3775);
PAINT SKYBLUE (-3625 3775);
DISPLAY INVISIBLE (-3625 3775);
FORCEPROP 1 LAST PART_NUMBER CS22202JB07
J 0
(-3675 3975);
DISPLAY 0.510638 (-3675 3975);
PAINT WHITE (-3675 3975);
DISPLAY INVISIBLE (-3675 3975);
FORCEPROP 1 LAST PACK_TYPE 0402LF
J 0
(-3375 3725);
DISPLAY 0.510638 (-3375 3725);
PAINT SKYBLUE (-3375 3725);
DISPLAY INVISIBLE (-3375 3725);
FORCEPROP 1 LAST WATTAGE 1/16W
J 2
(-3650 3725);
DISPLAY 0.510638 (-3650 3725);
PAINT SKYBLUE (-3650 3725);
DISPLAY INVISIBLE (-3650 3725);
FORCEPROP 1 LAST PATH I109
J 0
(-3675 4025);
DISPLAY 0.978723 (-3675 4025);
PAINT WHITE (-3675 4025);
DISPLAY INVISIBLE (-3675 4025);
FORCEPROP 2 LAST CDS_LIB pure_quanta
J 0
(-3625 3875);
DISPLAY INVISIBLE (-3625 3875);
FORCEPROP 1 LAST LOCATION R247
J 0
(-3975 3875);
DISPLAY 0.702128 (-3975 3875);
PAINT YELLOW (-3975 3875);
FORCEPROP 0 LAST $SEC 1
J 0
(-3900 3925);
DISPLAY INVISIBLE (-3900 3925);
FORCEPROP 0 LAST CDS_SEC 1
J 0
(-3900 3925);
DISPLAY INVISIBLE (-3900 3925);
FORCEPROP 1 LASTPIN (-3725 3875) $PN 1
J 0
(-3713 3887);
DISPLAY 0.808511 (-3713 3887);
PAINT WHITE (-3713 3887);
DISPLAY INVISIBLE (-3713 3887);
FORCEPROP 1 LASTPIN (-3525 3875) $PN 2
J 0
(-3563 3887);
DISPLAY 0.808511 (-3563 3887);
PAINT WHITE (-3563 3887);
DISPLAY INVISIBLE (-3563 3887);
FORCEADD UNIVERSAL_POWER..1
(-4075 4325);
FORCEPROP 3 LASTPIN (-4075 4275) SIG_NAME P3V3_AUX\g
J 0
(-4065 4285);
DISPLAY 0.659574 (-4065 4285);
PAINT MONO (-4065 4285);
DISPLAY INVISIBLE (-4065 4285);
FORCEPROP 1 LAST HDL_POWER P3V3_AUX
J 1
(-4075 4375);
DISPLAY 0.702128 (-4075 4375);
PAINT GREEN (-4075 4375);
FORCEPROP 1 LAST PATH I110
J 0
(-4025 4350);
DISPLAY 0.872340 (-4025 4350);
PAINT AQUA (-4025 4350);
DISPLAY INVISIBLE (-4025 4350);
FORCEPROP 2 LAST CDS_LIB logical_power
J 0
(-4075 4325);
DISPLAY INVISIBLE (-4075 4325);
FORCEADD OFFPAGE..2
(-2525 1125);
FORCEPROP 2 LAST $XR0 13 
J 0
(-2336 1125);
DISPLAY 0.638298 (-2336 1125);
PAINT MONO (-2336 1125);
FORCEPROP 2 LAST $XR1 35 
J 0
(-2246 1125);
DISPLAY 0.638298 (-2246 1125);
PAINT MONO (-2246 1125);
FORCEPROP 2 LAST CDS_LIB standard
J 0
(-2525 1125);
DISPLAY INVISIBLE (-2525 1125);
FORCEPROP 1 LAST OFFPAGE TRUE
J 0
(-2200 1000);
DISPLAY 0.872340 (-2200 1000);
PAINT GREEN (-2200 1000);
DISPLAY INVISIBLE (-2200 1000);
FORCEPROP 1 LAST COMMENT_BODY TRUE
J 0
(-2570 1030);
DISPLAY 0.872340 (-2570 1030);
PAINT PEACH (-2570 1030);
DISPLAY INVISIBLE (-2570 1030);
FORCEPROP 2 LAST PATH I119
J 0
(-2325 1175);
DISPLAY 1.021277 (-2325 1175);
DISPLAY INVISIBLE (-2325 1175);
FORCEADD OFFPAGE..2
(-2525 1200);
FORCEPROP 2 LAST $XR0 13 
J 0
(-2336 1200);
DISPLAY 0.638298 (-2336 1200);
PAINT MONO (-2336 1200);
FORCEPROP 2 LAST $XR1 35 
J 0
(-2246 1200);
DISPLAY 0.638298 (-2246 1200);
PAINT MONO (-2246 1200);
FORCEPROP 2 LAST CDS_LIB standard
J 0
(-2525 1200);
DISPLAY INVISIBLE (-2525 1200);
FORCEPROP 1 LAST OFFPAGE TRUE
J 0
(-2200 1075);
DISPLAY 0.872340 (-2200 1075);
PAINT GREEN (-2200 1075);
DISPLAY INVISIBLE (-2200 1075);
FORCEPROP 1 LAST COMMENT_BODY TRUE
J 0
(-2570 1105);
DISPLAY 0.872340 (-2570 1105);
PAINT PEACH (-2570 1105);
DISPLAY INVISIBLE (-2570 1105);
FORCEPROP 2 LAST PATH I120
J 0
(-2325 1250);
DISPLAY 1.021277 (-2325 1250);
DISPLAY INVISIBLE (-2325 1250);
FORCEADD OFFPAGE..2
(-2525 1275);
FORCEPROP 2 LAST $XR1 13 
J 0
(-2246 1275);
DISPLAY 0.638298 (-2246 1275);
PAINT MONO (-2246 1275);
FORCEPROP 2 LAST $XR0 35 
J 0
(-2336 1275);
DISPLAY 0.638298 (-2336 1275);
PAINT MONO (-2336 1275);
FORCEPROP 2 LAST CDS_LIB standard
J 0
(-2525 1275);
DISPLAY INVISIBLE (-2525 1275);
FORCEPROP 1 LAST OFFPAGE TRUE
J 0
(-2200 1150);
DISPLAY 0.872340 (-2200 1150);
PAINT GREEN (-2200 1150);
DISPLAY INVISIBLE (-2200 1150);
FORCEPROP 1 LAST COMMENT_BODY TRUE
J 0
(-2570 1180);
DISPLAY 0.872340 (-2570 1180);
PAINT PEACH (-2570 1180);
DISPLAY INVISIBLE (-2570 1180);
FORCEPROP 2 LAST PATH I121
J 0
(-2325 1325);
DISPLAY 1.021277 (-2325 1325);
DISPLAY INVISIBLE (-2325 1325);
FORCEADD OFFPAGE..2
(-2525 1350);
FORCEPROP 2 LAST $XR1 13 
J 0
(-2246 1350);
DISPLAY 0.638298 (-2246 1350);
PAINT MONO (-2246 1350);
FORCEPROP 2 LAST $XR0 34 
J 0
(-2336 1350);
DISPLAY 0.638298 (-2336 1350);
PAINT MONO (-2336 1350);
FORCEPROP 2 LAST CDS_LIB standard
J 0
(-2525 1350);
DISPLAY INVISIBLE (-2525 1350);
FORCEPROP 1 LAST OFFPAGE TRUE
J 0
(-2200 1225);
DISPLAY 0.872340 (-2200 1225);
PAINT GREEN (-2200 1225);
DISPLAY INVISIBLE (-2200 1225);
FORCEPROP 1 LAST COMMENT_BODY TRUE
J 0
(-2570 1255);
DISPLAY 0.872340 (-2570 1255);
PAINT PEACH (-2570 1255);
DISPLAY INVISIBLE (-2570 1255);
FORCEPROP 2 LAST PATH I122
J 0
(-2325 1400);
DISPLAY 1.021277 (-2325 1400);
DISPLAY INVISIBLE (-2325 1400);
FORCEADD OFFPAGE..2
(-1875 1675);
FORCEPROP 2 LAST $XR1 26 
J 0
(-1596 1675);
DISPLAY 0.638298 (-1596 1675);
PAINT MONO (-1596 1675);
FORCEPROP 2 LAST $XR0 12 
J 0
(-1686 1675);
DISPLAY 0.638298 (-1686 1675);
PAINT MONO (-1686 1675);
FORCEPROP 2 LAST PATH I123
J 0
(-1575 1725);
DISPLAY 1.021277 (-1575 1725);
DISPLAY INVISIBLE (-1575 1725);
FORCEPROP 1 LAST COMMENT_BODY TRUE
J 0
(-1920 1580);
DISPLAY 0.872340 (-1920 1580);
PAINT PEACH (-1920 1580);
DISPLAY INVISIBLE (-1920 1580);
FORCEPROP 1 LAST OFFPAGE TRUE
J 0
(-1550 1550);
DISPLAY 0.872340 (-1550 1550);
PAINT GREEN (-1550 1550);
DISPLAY INVISIBLE (-1550 1550);
FORCEPROP 2 LAST CDS_LIB standard
J 0
(-1875 1675);
DISPLAY INVISIBLE (-1875 1675);
FORCEADD OFFPAGE..2
(-1875 1775);
FORCEPROP 2 LAST $XR0 12 
J 0
(-1686 1775);
DISPLAY 0.638298 (-1686 1775);
PAINT MONO (-1686 1775);
FORCEPROP 2 LAST $XR1 26 
J 0
(-1596 1775);
DISPLAY 0.638298 (-1596 1775);
PAINT MONO (-1596 1775);
FORCEPROP 2 LAST PATH I124
J 0
(-1575 1825);
DISPLAY 1.021277 (-1575 1825);
DISPLAY INVISIBLE (-1575 1825);
FORCEPROP 1 LAST COMMENT_BODY TRUE
J 0
(-1920 1680);
DISPLAY 0.872340 (-1920 1680);
PAINT PEACH (-1920 1680);
DISPLAY INVISIBLE (-1920 1680);
FORCEPROP 1 LAST OFFPAGE TRUE
J 0
(-1550 1650);
DISPLAY 0.872340 (-1550 1650);
PAINT GREEN (-1550 1650);
DISPLAY INVISIBLE (-1550 1650);
FORCEPROP 2 LAST CDS_LIB standard
J 0
(-1875 1775);
DISPLAY INVISIBLE (-1875 1775);
FORCEADD OFFPAGE..2
(-1875 2475);
FORCEPROP 2 LAST $XR0 10 
J 0
(-1686 2475);
DISPLAY 0.638298 (-1686 2475);
PAINT MONO (-1686 2475);
FORCEPROP 2 LAST $XR1 12 
J 0
(-1596 2475);
DISPLAY 0.638298 (-1596 2475);
PAINT MONO (-1596 2475);
FORCEPROP 2 LAST PATH I125
J 0
(-1625 2525);
DISPLAY 1.021277 (-1625 2525);
DISPLAY INVISIBLE (-1625 2525);
FORCEPROP 1 LAST COMMENT_BODY TRUE
J 0
(-1920 2380);
DISPLAY 0.872340 (-1920 2380);
PAINT PEACH (-1920 2380);
DISPLAY INVISIBLE (-1920 2380);
FORCEPROP 1 LAST OFFPAGE TRUE
J 0
(-1550 2350);
DISPLAY 0.872340 (-1550 2350);
PAINT GREEN (-1550 2350);
DISPLAY INVISIBLE (-1550 2350);
FORCEPROP 2 LAST CDS_LIB standard
J 0
(-1875 2475);
DISPLAY INVISIBLE (-1875 2475);
FORCEADD OFFPAGE..2
(-1875 2375);
FORCEPROP 2 LAST $XR1 10 
J 0
(-1596 2375);
DISPLAY 0.638298 (-1596 2375);
PAINT MONO (-1596 2375);
FORCEPROP 2 LAST $XR0 12 
J 0
(-1686 2375);
DISPLAY 0.638298 (-1686 2375);
PAINT MONO (-1686 2375);
FORCEPROP 2 LAST PATH I126
J 0
(-1575 2425);
DISPLAY 1.021277 (-1575 2425);
DISPLAY INVISIBLE (-1575 2425);
FORCEPROP 1 LAST COMMENT_BODY TRUE
J 0
(-1920 2280);
DISPLAY 0.872340 (-1920 2280);
PAINT PEACH (-1920 2280);
DISPLAY INVISIBLE (-1920 2280);
FORCEPROP 1 LAST OFFPAGE TRUE
J 0
(-1550 2250);
DISPLAY 0.872340 (-1550 2250);
PAINT GREEN (-1550 2250);
DISPLAY INVISIBLE (-1550 2250);
FORCEPROP 2 LAST CDS_LIB standard
J 0
(-1875 2375);
DISPLAY INVISIBLE (-1875 2375);
FORCEADD OFFPAGE..2
(-1875 2275);
FORCEPROP 2 LAST $XR0 10 
J 0
(-1686 2275);
DISPLAY 0.638298 (-1686 2275);
PAINT MONO (-1686 2275);
FORCEPROP 2 LAST $XR1 12 
J 0
(-1596 2275);
DISPLAY 0.638298 (-1596 2275);
PAINT MONO (-1596 2275);
FORCEPROP 2 LAST PATH I127
J 0
(-1625 2325);
DISPLAY 1.021277 (-1625 2325);
DISPLAY INVISIBLE (-1625 2325);
FORCEPROP 1 LAST COMMENT_BODY TRUE
J 0
(-1920 2180);
DISPLAY 0.872340 (-1920 2180);
PAINT PEACH (-1920 2180);
DISPLAY INVISIBLE (-1920 2180);
FORCEPROP 1 LAST OFFPAGE TRUE
J 0
(-1550 2150);
DISPLAY 0.872340 (-1550 2150);
PAINT GREEN (-1550 2150);
DISPLAY INVISIBLE (-1550 2150);
FORCEPROP 2 LAST CDS_LIB standard
J 0
(-1875 2275);
DISPLAY INVISIBLE (-1875 2275);
FORCEADD OFFPAGE..2
(-1875 1875);
FORCEPROP 2 LAST $XR1 28 
J 0
(-1596 1875);
DISPLAY 0.638298 (-1596 1875);
PAINT MONO (-1596 1875);
FORCEPROP 2 LAST $XR0 12 
J 0
(-1686 1875);
DISPLAY 0.638298 (-1686 1875);
PAINT MONO (-1686 1875);
FORCEPROP 2 LAST PATH I128
J 0
(-1400 1925);
DISPLAY 1.021277 (-1400 1925);
DISPLAY INVISIBLE (-1400 1925);
FORCEPROP 1 LAST COMMENT_BODY TRUE
J 0
(-1920 1780);
DISPLAY 0.872340 (-1920 1780);
PAINT PEACH (-1920 1780);
DISPLAY INVISIBLE (-1920 1780);
FORCEPROP 1 LAST OFFPAGE TRUE
J 0
(-1550 1750);
DISPLAY 0.872340 (-1550 1750);
PAINT GREEN (-1550 1750);
DISPLAY INVISIBLE (-1550 1750);
FORCEPROP 2 LAST CDS_LIB standard
J 0
(-1875 1875);
DISPLAY INVISIBLE (-1875 1875);
FORCEADD OFFPAGE..2
(-1875 1975);
FORCEPROP 2 LAST $XR0 12 
J 0
(-1686 1975);
DISPLAY 0.638298 (-1686 1975);
PAINT MONO (-1686 1975);
FORCEPROP 2 LAST $XR1 28 
J 0
(-1596 1975);
DISPLAY 0.638298 (-1596 1975);
PAINT MONO (-1596 1975);
FORCEPROP 2 LAST PATH I129
J 0
(-1400 2025);
DISPLAY 1.021277 (-1400 2025);
DISPLAY INVISIBLE (-1400 2025);
FORCEPROP 1 LAST COMMENT_BODY TRUE
J 0
(-1920 1880);
DISPLAY 0.872340 (-1920 1880);
PAINT PEACH (-1920 1880);
DISPLAY INVISIBLE (-1920 1880);
FORCEPROP 1 LAST OFFPAGE TRUE
J 0
(-1550 1850);
DISPLAY 0.872340 (-1550 1850);
PAINT GREEN (-1550 1850);
DISPLAY INVISIBLE (-1550 1850);
FORCEPROP 2 LAST CDS_LIB standard
J 0
(-1875 1975);
DISPLAY INVISIBLE (-1875 1975);
FORCEADD OFFPAGE..2
(-1875 2575);
FORCEPROP 2 LAST $XR0 12 
J 0
(-1686 2575);
DISPLAY 0.638298 (-1686 2575);
PAINT MONO (-1686 2575);
FORCEPROP 2 LAST $XR1 10 
J 0
(-1596 2575);
DISPLAY 0.638298 (-1596 2575);
PAINT MONO (-1596 2575);
FORCEPROP 2 LAST PATH I130
J 0
(-1575 2625);
DISPLAY 1.021277 (-1575 2625);
DISPLAY INVISIBLE (-1575 2625);
FORCEPROP 1 LAST COMMENT_BODY TRUE
J 0
(-1920 2480);
DISPLAY 0.872340 (-1920 2480);
PAINT PEACH (-1920 2480);
DISPLAY INVISIBLE (-1920 2480);
FORCEPROP 1 LAST OFFPAGE TRUE
J 0
(-1550 2450);
DISPLAY 0.872340 (-1550 2450);
PAINT GREEN (-1550 2450);
DISPLAY INVISIBLE (-1550 2450);
FORCEPROP 2 LAST CDS_LIB standard
J 0
(-1875 2575);
DISPLAY INVISIBLE (-1875 2575);
FORCEADD OFFPAGE..2
(-1875 2875);
FORCEPROP 2 LAST $XR0 12 
J 0
(-1686 2875);
DISPLAY 0.638298 (-1686 2875);
PAINT MONO (-1686 2875);
FORCEPROP 2 LAST PATH I131
J 0
(-1625 2925);
DISPLAY 1.021277 (-1625 2925);
DISPLAY INVISIBLE (-1625 2925);
FORCEPROP 1 LAST COMMENT_BODY TRUE
J 0
(-1920 2780);
DISPLAY 0.872340 (-1920 2780);
PAINT PEACH (-1920 2780);
DISPLAY INVISIBLE (-1920 2780);
FORCEPROP 1 LAST OFFPAGE TRUE
J 0
(-1550 2750);
DISPLAY 0.872340 (-1550 2750);
PAINT GREEN (-1550 2750);
DISPLAY INVISIBLE (-1550 2750);
FORCEPROP 2 LAST CDS_LIB standard
J 0
(-1875 2875);
DISPLAY INVISIBLE (-1875 2875);
FORCEADD OFFPAGE..2
(-1875 2775);
FORCEPROP 2 LAST $XR1 10 
J 0
(-1596 2775);
DISPLAY 0.638298 (-1596 2775);
PAINT MONO (-1596 2775);
FORCEPROP 2 LAST $XR0 12 
J 0
(-1686 2775);
DISPLAY 0.638298 (-1686 2775);
PAINT MONO (-1686 2775);
FORCEPROP 2 LAST PATH I132
J 0
(-1575 2825);
DISPLAY 1.021277 (-1575 2825);
DISPLAY INVISIBLE (-1575 2825);
FORCEPROP 1 LAST COMMENT_BODY TRUE
J 0
(-1920 2680);
DISPLAY 0.872340 (-1920 2680);
PAINT PEACH (-1920 2680);
DISPLAY INVISIBLE (-1920 2680);
FORCEPROP 1 LAST OFFPAGE TRUE
J 0
(-1550 2650);
DISPLAY 0.872340 (-1550 2650);
PAINT GREEN (-1550 2650);
DISPLAY INVISIBLE (-1550 2650);
FORCEPROP 2 LAST CDS_LIB standard
J 0
(-1875 2775);
DISPLAY INVISIBLE (-1875 2775);
FORCEADD OFFPAGE..2
(-1875 2975);
FORCEPROP 2 LAST $XR0 12 
J 0
(-1686 2975);
DISPLAY 0.638298 (-1686 2975);
PAINT MONO (-1686 2975);
FORCEPROP 2 LAST PATH I133
J 0
(-1575 3025);
DISPLAY 1.021277 (-1575 3025);
DISPLAY INVISIBLE (-1575 3025);
FORCEPROP 1 LAST COMMENT_BODY TRUE
J 0
(-1920 2880);
DISPLAY 0.872340 (-1920 2880);
PAINT PEACH (-1920 2880);
DISPLAY INVISIBLE (-1920 2880);
FORCEPROP 1 LAST OFFPAGE TRUE
J 0
(-1550 2850);
DISPLAY 0.872340 (-1550 2850);
PAINT GREEN (-1550 2850);
DISPLAY INVISIBLE (-1550 2850);
FORCEPROP 2 LAST CDS_LIB standard
J 0
(-1875 2975);
DISPLAY INVISIBLE (-1875 2975);
FORCEADD OFFPAGE..2
(-1875 2675);
FORCEPROP 2 LAST $XR1 12 
J 0
(-1596 2675);
DISPLAY 0.638298 (-1596 2675);
PAINT MONO (-1596 2675);
FORCEPROP 2 LAST $XR0 10 
J 0
(-1686 2675);
DISPLAY 0.638298 (-1686 2675);
PAINT MONO (-1686 2675);
FORCEPROP 2 LAST PATH I134
J 0
(-1625 2725);
DISPLAY 1.021277 (-1625 2725);
DISPLAY INVISIBLE (-1625 2725);
FORCEPROP 1 LAST COMMENT_BODY TRUE
J 0
(-1920 2580);
DISPLAY 0.872340 (-1920 2580);
PAINT PEACH (-1920 2580);
DISPLAY INVISIBLE (-1920 2580);
FORCEPROP 1 LAST OFFPAGE TRUE
J 0
(-1550 2550);
DISPLAY 0.872340 (-1550 2550);
PAINT GREEN (-1550 2550);
DISPLAY INVISIBLE (-1550 2550);
FORCEPROP 2 LAST CDS_LIB standard
J 0
(-1875 2675);
DISPLAY INVISIBLE (-1875 2675);
FORCEADD OFFPAGE..2
(-1875 3075);
FORCEPROP 2 LAST $XR1 12 
J 0
(-1596 3075);
DISPLAY 0.638298 (-1596 3075);
PAINT MONO (-1596 3075);
FORCEPROP 2 LAST $XR0 10 
J 0
(-1686 3075);
DISPLAY 0.638298 (-1686 3075);
PAINT MONO (-1686 3075);
FORCEPROP 2 LAST PATH I135
J 0
(-1625 3125);
DISPLAY 1.021277 (-1625 3125);
DISPLAY INVISIBLE (-1625 3125);
FORCEPROP 1 LAST COMMENT_BODY TRUE
J 0
(-1920 2980);
DISPLAY 0.872340 (-1920 2980);
PAINT PEACH (-1920 2980);
DISPLAY INVISIBLE (-1920 2980);
FORCEPROP 1 LAST OFFPAGE TRUE
J 0
(-1550 2950);
DISPLAY 0.872340 (-1550 2950);
PAINT GREEN (-1550 2950);
DISPLAY INVISIBLE (-1550 2950);
FORCEPROP 2 LAST CDS_LIB standard
J 0
(-1875 3075);
DISPLAY INVISIBLE (-1875 3075);
FORCEADD OFFPAGE..2
(-1875 3375);
FORCEPROP 2 LAST $XR0 12 
J 0
(-1686 3375);
DISPLAY 0.638298 (-1686 3375);
PAINT MONO (-1686 3375);
FORCEPROP 2 LAST PATH I136
J 0
(-1575 3425);
DISPLAY 1.021277 (-1575 3425);
DISPLAY INVISIBLE (-1575 3425);
FORCEPROP 1 LAST COMMENT_BODY TRUE
J 0
(-1920 3280);
DISPLAY 0.872340 (-1920 3280);
PAINT PEACH (-1920 3280);
DISPLAY INVISIBLE (-1920 3280);
FORCEPROP 1 LAST OFFPAGE TRUE
J 0
(-1550 3250);
DISPLAY 0.872340 (-1550 3250);
PAINT GREEN (-1550 3250);
DISPLAY INVISIBLE (-1550 3250);
FORCEPROP 2 LAST CDS_LIB standard
J 0
(-1875 3375);
DISPLAY INVISIBLE (-1875 3375);
FORCEADD OFFPAGE..2
(-1875 3475);
FORCEPROP 2 LAST $XR1 12 
J 0
(-1596 3475);
DISPLAY 0.638298 (-1596 3475);
PAINT MONO (-1596 3475);
FORCEPROP 2 LAST $XR0 10 
J 0
(-1686 3475);
DISPLAY 0.638298 (-1686 3475);
PAINT MONO (-1686 3475);
FORCEPROP 2 LAST PATH I137
J 0
(-1625 3525);
DISPLAY 1.021277 (-1625 3525);
DISPLAY INVISIBLE (-1625 3525);
FORCEPROP 1 LAST COMMENT_BODY TRUE
J 0
(-1920 3380);
DISPLAY 0.872340 (-1920 3380);
PAINT PEACH (-1920 3380);
DISPLAY INVISIBLE (-1920 3380);
FORCEPROP 1 LAST OFFPAGE TRUE
J 0
(-1550 3350);
DISPLAY 0.872340 (-1550 3350);
PAINT GREEN (-1550 3350);
DISPLAY INVISIBLE (-1550 3350);
FORCEPROP 2 LAST CDS_LIB standard
J 0
(-1875 3475);
DISPLAY INVISIBLE (-1875 3475);
FORCEADD OFFPAGE..2
(-1875 3575);
FORCEPROP 2 LAST $XR1 10 
J 0
(-1596 3575);
DISPLAY 0.638298 (-1596 3575);
PAINT MONO (-1596 3575);
FORCEPROP 2 LAST $XR0 12 
J 0
(-1686 3575);
DISPLAY 0.638298 (-1686 3575);
PAINT MONO (-1686 3575);
FORCEPROP 2 LAST PATH I138
J 0
(-1575 3625);
DISPLAY 1.021277 (-1575 3625);
DISPLAY INVISIBLE (-1575 3625);
FORCEPROP 1 LAST COMMENT_BODY TRUE
J 0
(-1920 3480);
DISPLAY 0.872340 (-1920 3480);
PAINT PEACH (-1920 3480);
DISPLAY INVISIBLE (-1920 3480);
FORCEPROP 1 LAST OFFPAGE TRUE
J 0
(-1550 3450);
DISPLAY 0.872340 (-1550 3450);
PAINT GREEN (-1550 3450);
DISPLAY INVISIBLE (-1550 3450);
FORCEPROP 2 LAST CDS_LIB standard
J 0
(-1875 3575);
DISPLAY INVISIBLE (-1875 3575);
FORCEADD OFFPAGE..2
(-1875 3675);
FORCEPROP 2 LAST $XR1 10 
J 0
(-1596 3675);
DISPLAY 0.638298 (-1596 3675);
PAINT MONO (-1596 3675);
FORCEPROP 2 LAST $XR0 12 
J 0
(-1686 3675);
DISPLAY 0.638298 (-1686 3675);
PAINT MONO (-1686 3675);
FORCEPROP 2 LAST PATH I139
J 0
(-1525 3725);
DISPLAY 1.021277 (-1525 3725);
DISPLAY INVISIBLE (-1525 3725);
FORCEPROP 1 LAST COMMENT_BODY TRUE
J 0
(-1920 3580);
DISPLAY 0.872340 (-1920 3580);
PAINT PEACH (-1920 3580);
DISPLAY INVISIBLE (-1920 3580);
FORCEPROP 1 LAST OFFPAGE TRUE
J 0
(-1550 3550);
DISPLAY 0.872340 (-1550 3550);
PAINT GREEN (-1550 3550);
DISPLAY INVISIBLE (-1550 3550);
FORCEPROP 2 LAST CDS_LIB standard
J 0
(-1875 3675);
DISPLAY INVISIBLE (-1875 3675);
FORCEADD OFFPAGE..1
(1925 2000);
FORCEPROP 2 LAST $XR0 48 
J 0
(1674 2000);
DISPLAY 0.638298 (1674 2000);
PAINT MONO (1674 2000);
FORCEPROP 2 LAST PATH I14
J 0
(1975 2075);
DISPLAY 1.021277 (1975 2075);
DISPLAY INVISIBLE (1975 2075);
FORCEPROP 1 LAST COMMENT_BODY TRUE
J 0
(2050 1900);
DISPLAY 0.872340 (2050 1900);
PAINT PEACH (2050 1900);
DISPLAY INVISIBLE (2050 1900);
FORCEPROP 1 LAST OFFPAGE TRUE
J 0
(2250 1875);
DISPLAY 0.872340 (2250 1875);
PAINT GREEN (2250 1875);
DISPLAY INVISIBLE (2250 1875);
FORCEPROP 2 LAST CDS_LIB standard
J 0
(1925 2000);
DISPLAY INVISIBLE (1925 2000);
FORCEADD OFFPAGE..2
(-1875 3775);
FORCEPROP 2 LAST $XR0 10 
J 0
(-1686 3775);
DISPLAY 0.638298 (-1686 3775);
PAINT MONO (-1686 3775);
FORCEPROP 2 LAST $XR1 12 
J 0
(-1596 3775);
DISPLAY 0.638298 (-1596 3775);
PAINT MONO (-1596 3775);
FORCEPROP 2 LAST PATH I140
J 0
(-1500 3825);
DISPLAY 1.021277 (-1500 3825);
DISPLAY INVISIBLE (-1500 3825);
FORCEPROP 1 LAST COMMENT_BODY TRUE
J 0
(-1920 3680);
DISPLAY 0.872340 (-1920 3680);
PAINT PEACH (-1920 3680);
DISPLAY INVISIBLE (-1920 3680);
FORCEPROP 1 LAST OFFPAGE TRUE
J 0
(-1550 3650);
DISPLAY 0.872340 (-1550 3650);
PAINT GREEN (-1550 3650);
DISPLAY INVISIBLE (-1550 3650);
FORCEPROP 2 LAST CDS_LIB standard
J 0
(-1875 3775);
DISPLAY INVISIBLE (-1875 3775);
FORCEADD OFFPAGE..2
(-1875 3975);
FORCEPROP 2 LAST $XR2 26 
J 0
(-1506 3975);
DISPLAY 0.638298 (-1506 3975);
PAINT MONO (-1506 3975);
FORCEPROP 2 LAST $XR1 12 
J 0
(-1596 3975);
DISPLAY 0.638298 (-1596 3975);
PAINT MONO (-1596 3975);
FORCEPROP 2 LAST $XR0 10 
J 0
(-1686 3975);
DISPLAY 0.638298 (-1686 3975);
PAINT MONO (-1686 3975);
FORCEPROP 2 LAST PATH I141
J 0
(-1500 4025);
DISPLAY 1.021277 (-1500 4025);
DISPLAY INVISIBLE (-1500 4025);
FORCEPROP 1 LAST COMMENT_BODY TRUE
J 0
(-1920 3880);
DISPLAY 0.872340 (-1920 3880);
PAINT PEACH (-1920 3880);
DISPLAY INVISIBLE (-1920 3880);
FORCEPROP 1 LAST OFFPAGE TRUE
J 0
(-1550 3850);
DISPLAY 0.872340 (-1550 3850);
PAINT GREEN (-1550 3850);
DISPLAY INVISIBLE (-1550 3850);
FORCEPROP 2 LAST CDS_LIB standard
J 0
(-1875 3975);
DISPLAY INVISIBLE (-1875 3975);
FORCEADD OFFPAGE..2
(-1875 3875);
FORCEPROP 2 LAST $XR2 10 
J 0
(-1506 3875);
DISPLAY 0.638298 (-1506 3875);
PAINT MONO (-1506 3875);
FORCEPROP 2 LAST $XR1 26 
J 0
(-1596 3875);
DISPLAY 0.638298 (-1596 3875);
PAINT MONO (-1596 3875);
FORCEPROP 2 LAST $XR0 12 
J 0
(-1686 3875);
DISPLAY 0.638298 (-1686 3875);
PAINT MONO (-1686 3875);
FORCEPROP 2 LAST PATH I142
J 0
(-1525 3925);
DISPLAY 1.021277 (-1525 3925);
DISPLAY INVISIBLE (-1525 3925);
FORCEPROP 1 LAST COMMENT_BODY TRUE
J 0
(-1920 3780);
DISPLAY 0.872340 (-1920 3780);
PAINT PEACH (-1920 3780);
DISPLAY INVISIBLE (-1920 3780);
FORCEPROP 1 LAST OFFPAGE TRUE
J 0
(-1550 3750);
DISPLAY 0.872340 (-1550 3750);
PAINT GREEN (-1550 3750);
DISPLAY INVISIBLE (-1550 3750);
FORCEPROP 2 LAST CDS_LIB standard
J 0
(-1875 3875);
DISPLAY INVISIBLE (-1875 3875);
FORCEADD OFFPAGE..2
(-1875 4075);
FORCEPROP 2 LAST $XR1 12 
J 0
(-1596 4075);
DISPLAY 0.638298 (-1596 4075);
PAINT MONO (-1596 4075);
FORCEPROP 2 LAST $XR0 10 
J 0
(-1686 4075);
DISPLAY 0.638298 (-1686 4075);
PAINT MONO (-1686 4075);
FORCEPROP 2 LAST PATH I143
J 0
(-1525 4125);
DISPLAY 1.021277 (-1525 4125);
DISPLAY INVISIBLE (-1525 4125);
FORCEPROP 1 LAST COMMENT_BODY TRUE
J 0
(-1920 3980);
DISPLAY 0.872340 (-1920 3980);
PAINT PEACH (-1920 3980);
DISPLAY INVISIBLE (-1920 3980);
FORCEPROP 1 LAST OFFPAGE TRUE
J 0
(-1550 3950);
DISPLAY 0.872340 (-1550 3950);
PAINT GREEN (-1550 3950);
DISPLAY INVISIBLE (-1550 3950);
FORCEPROP 2 LAST CDS_LIB standard
J 0
(-1875 4075);
DISPLAY INVISIBLE (-1875 4075);
FORCEADD OFFPAGE..2
(-1875 4175);
FORCEPROP 2 LAST $XR1 10 
J 0
(-1596 4175);
DISPLAY 0.638298 (-1596 4175);
PAINT MONO (-1596 4175);
FORCEPROP 2 LAST $XR0 12 
J 0
(-1686 4175);
DISPLAY 0.638298 (-1686 4175);
PAINT MONO (-1686 4175);
FORCEPROP 2 LAST PATH I144
J 0
(-1500 4225);
DISPLAY 1.021277 (-1500 4225);
DISPLAY INVISIBLE (-1500 4225);
FORCEPROP 1 LAST COMMENT_BODY TRUE
J 0
(-1920 4080);
DISPLAY 0.872340 (-1920 4080);
PAINT PEACH (-1920 4080);
DISPLAY INVISIBLE (-1920 4080);
FORCEPROP 1 LAST OFFPAGE TRUE
J 0
(-1550 4050);
DISPLAY 0.872340 (-1550 4050);
PAINT GREEN (-1550 4050);
DISPLAY INVISIBLE (-1550 4050);
FORCEPROP 2 LAST CDS_LIB standard
J 0
(-1875 4175);
DISPLAY INVISIBLE (-1875 4175);
FORCEADD Q_RES..1
(-3625 3975);
FORCEPROP 1 LAST VALUE 2.2K
J 2
(-3750 3975);
DISPLAY 0.510638 (-3750 3975);
PAINT SKYBLUE (-3750 3975);
FORCEPROP 1 LAST MATERIAL CHIP
J 0
(-3500 3975);
DISPLAY 0.510638 (-3500 3975);
PAINT SKYBLUE (-3500 3975);
FORCEPROP 1 LAST TOLERANCE 5%
J 0
(-3625 3875);
DISPLAY 0.510638 (-3625 3875);
PAINT SKYBLUE (-3625 3875);
DISPLAY INVISIBLE (-3625 3875);
FORCEPROP 1 LAST PART_NUMBER CS22202JB07
J 0
(-3675 4075);
DISPLAY 0.510638 (-3675 4075);
PAINT WHITE (-3675 4075);
DISPLAY INVISIBLE (-3675 4075);
FORCEPROP 1 LAST PACK_TYPE 0402LF
J 0
(-3375 3825);
DISPLAY 0.510638 (-3375 3825);
PAINT SKYBLUE (-3375 3825);
DISPLAY INVISIBLE (-3375 3825);
FORCEPROP 1 LAST WATTAGE 1/16W
J 2
(-3650 3825);
DISPLAY 0.510638 (-3650 3825);
PAINT SKYBLUE (-3650 3825);
DISPLAY INVISIBLE (-3650 3825);
FORCEPROP 1 LAST PATH I145
J 0
(-3675 4125);
DISPLAY 0.978723 (-3675 4125);
PAINT WHITE (-3675 4125);
DISPLAY INVISIBLE (-3675 4125);
FORCEPROP 2 LAST CDS_LIB pure_quanta
J 0
(-3625 3975);
DISPLAY INVISIBLE (-3625 3975);
FORCEPROP 1 LAST LOCATION R246
J 0
(-3975 3975);
DISPLAY 0.702128 (-3975 3975);
PAINT YELLOW (-3975 3975);
FORCEPROP 0 LAST $SEC 1
J 0
(-3900 4025);
DISPLAY INVISIBLE (-3900 4025);
FORCEPROP 0 LAST CDS_SEC 1
J 0
(-3900 4025);
DISPLAY INVISIBLE (-3900 4025);
FORCEPROP 1 LASTPIN (-3725 3975) $PN 1
J 0
(-3713 3987);
DISPLAY 0.808511 (-3713 3987);
PAINT WHITE (-3713 3987);
DISPLAY INVISIBLE (-3713 3987);
FORCEPROP 1 LASTPIN (-3525 3975) $PN 2
J 0
(-3563 3987);
DISPLAY 0.808511 (-3563 3987);
PAINT WHITE (-3563 3987);
DISPLAY INVISIBLE (-3563 3987);
FORCEADD Q_RES..1
(-3625 4075);
FORCEPROP 1 LAST VALUE 1.8K
J 2
(-3750 4075);
DISPLAY 0.510638 (-3750 4075);
PAINT SKYBLUE (-3750 4075);
FORCEPROP 1 LAST MATERIAL CHIP
J 0
(-3500 4075);
DISPLAY 0.510638 (-3500 4075);
PAINT SKYBLUE (-3500 4075);
FORCEPROP 2 LAST CDS_LIB pure_quanta
J 0
(-3625 4075);
DISPLAY INVISIBLE (-3625 4075);
FORCEPROP 1 LAST PATH I146
J 0
(-3675 4225);
DISPLAY 0.978723 (-3675 4225);
PAINT WHITE (-3675 4225);
DISPLAY INVISIBLE (-3675 4225);
FORCEPROP 1 LAST WATTAGE 1/16W
J 2
(-3650 3925);
DISPLAY 0.510638 (-3650 3925);
PAINT SKYBLUE (-3650 3925);
DISPLAY INVISIBLE (-3650 3925);
FORCEPROP 1 LAST PACK_TYPE 0402LF
J 0
(-3375 3925);
DISPLAY 0.510638 (-3375 3925);
PAINT SKYBLUE (-3375 3925);
DISPLAY INVISIBLE (-3375 3925);
FORCEPROP 1 LAST TOLERANCE 1%
J 0
(-3625 3975);
DISPLAY 0.510638 (-3625 3975);
PAINT SKYBLUE (-3625 3975);
DISPLAY INVISIBLE (-3625 3975);
FORCEPROP 1 LAST PART_NUMBER CS21802FB10
J 0
(-3675 4175);
DISPLAY 0.510638 (-3675 4175);
PAINT WHITE (-3675 4175);
DISPLAY INVISIBLE (-3675 4175);
FORCEPROP 1 LAST LOCATION R245
J 0
(-3975 4075);
DISPLAY 0.702128 (-3975 4075);
PAINT YELLOW (-3975 4075);
FORCEPROP 0 LAST $SEC 1
J 0
(-3900 4125);
DISPLAY INVISIBLE (-3900 4125);
FORCEPROP 0 LAST CDS_SEC 1
J 0
(-3900 4125);
DISPLAY INVISIBLE (-3900 4125);
FORCEPROP 1 LASTPIN (-3725 4075) $PN 1
J 0
(-3713 4087);
DISPLAY 0.808511 (-3713 4087);
PAINT WHITE (-3713 4087);
DISPLAY INVISIBLE (-3713 4087);
FORCEPROP 1 LASTPIN (-3525 4075) $PN 2
J 0
(-3563 4087);
DISPLAY 0.808511 (-3563 4087);
PAINT WHITE (-3563 4087);
DISPLAY INVISIBLE (-3563 4087);
FORCEADD Q_RES..1
(-3625 4175);
FORCEPROP 1 LAST MATERIAL CHIP
J 0
(-3500 4175);
DISPLAY 0.510638 (-3500 4175);
PAINT SKYBLUE (-3500 4175);
FORCEPROP 1 LAST VALUE 1.8K
J 2
(-3750 4175);
DISPLAY 0.510638 (-3750 4175);
PAINT SKYBLUE (-3750 4175);
FORCEPROP 2 LAST CDS_LIB pure_quanta
J 0
(-3625 4175);
DISPLAY INVISIBLE (-3625 4175);
FORCEPROP 1 LAST PATH I147
J 0
(-3675 4325);
DISPLAY 0.978723 (-3675 4325);
PAINT WHITE (-3675 4325);
DISPLAY INVISIBLE (-3675 4325);
FORCEPROP 1 LAST WATTAGE 1/16W
J 2
(-3650 4025);
DISPLAY 0.510638 (-3650 4025);
PAINT SKYBLUE (-3650 4025);
DISPLAY INVISIBLE (-3650 4025);
FORCEPROP 1 LAST PACK_TYPE 0402LF
J 0
(-3375 4025);
DISPLAY 0.510638 (-3375 4025);
PAINT SKYBLUE (-3375 4025);
DISPLAY INVISIBLE (-3375 4025);
FORCEPROP 1 LAST TOLERANCE 1%
J 0
(-3625 4075);
DISPLAY 0.510638 (-3625 4075);
PAINT SKYBLUE (-3625 4075);
DISPLAY INVISIBLE (-3625 4075);
FORCEPROP 1 LAST PART_NUMBER CS21802FB10
J 0
(-3675 4275);
DISPLAY 0.510638 (-3675 4275);
PAINT WHITE (-3675 4275);
DISPLAY INVISIBLE (-3675 4275);
FORCEPROP 1 LAST LOCATION R244
J 0
(-3975 4175);
DISPLAY 0.702128 (-3975 4175);
PAINT YELLOW (-3975 4175);
FORCEPROP 0 LAST $SEC 1
J 0
(-3900 4225);
DISPLAY INVISIBLE (-3900 4225);
FORCEPROP 0 LAST CDS_SEC 1
J 0
(-3900 4225);
DISPLAY INVISIBLE (-3900 4225);
FORCEPROP 1 LASTPIN (-3725 4175) $PN 1
J 0
(-3713 4187);
DISPLAY 0.808511 (-3713 4187);
PAINT WHITE (-3713 4187);
DISPLAY INVISIBLE (-3713 4187);
FORCEPROP 1 LASTPIN (-3525 4175) $PN 2
J 0
(-3563 4187);
DISPLAY 0.808511 (-3563 4187);
PAINT WHITE (-3563 4187);
DISPLAY INVISIBLE (-3563 4187);
FORCEADD OFFPAGE..2
(-1875 3175);
FORCEPROP 2 LAST $XR1 10 
J 0
(-1596 3175);
DISPLAY 0.638298 (-1596 3175);
PAINT MONO (-1596 3175);
FORCEPROP 2 LAST $XR0 12 
J 0
(-1686 3175);
DISPLAY 0.638298 (-1686 3175);
PAINT MONO (-1686 3175);
FORCEPROP 2 LAST PATH I148
J 0
(-1575 3225);
DISPLAY 1.021277 (-1575 3225);
DISPLAY INVISIBLE (-1575 3225);
FORCEPROP 1 LAST COMMENT_BODY TRUE
J 0
(-1920 3080);
DISPLAY 0.872340 (-1920 3080);
PAINT PEACH (-1920 3080);
DISPLAY INVISIBLE (-1920 3080);
FORCEPROP 1 LAST OFFPAGE TRUE
J 0
(-1550 3050);
DISPLAY 0.872340 (-1550 3050);
PAINT GREEN (-1550 3050);
DISPLAY INVISIBLE (-1550 3050);
FORCEPROP 2 LAST CDS_LIB standard
J 0
(-1875 3175);
DISPLAY INVISIBLE (-1875 3175);
FORCEADD OFFPAGE..2
(-1875 2075);
FORCEPROP 2 LAST $XR1 12 
J 0
(-1596 2075);
DISPLAY 0.638298 (-1596 2075);
PAINT MONO (-1596 2075);
FORCEPROP 2 LAST $XR0 10 
J 0
(-1686 2075);
DISPLAY 0.638298 (-1686 2075);
PAINT MONO (-1686 2075);
FORCEPROP 2 LAST PATH I155
J 0
(-1625 2125);
DISPLAY 1.021277 (-1625 2125);
DISPLAY INVISIBLE (-1625 2125);
FORCEPROP 1 LAST COMMENT_BODY TRUE
J 0
(-1920 1980);
DISPLAY 0.872340 (-1920 1980);
PAINT PEACH (-1920 1980);
DISPLAY INVISIBLE (-1920 1980);
FORCEPROP 1 LAST OFFPAGE TRUE
J 0
(-1550 1950);
DISPLAY 0.872340 (-1550 1950);
PAINT GREEN (-1550 1950);
DISPLAY INVISIBLE (-1550 1950);
FORCEPROP 2 LAST CDS_LIB standard
J 0
(-1875 2075);
DISPLAY INVISIBLE (-1875 2075);
FORCEADD OFFPAGE..2
(-1875 2175);
FORCEPROP 2 LAST $XR1 10 
J 0
(-1596 2175);
DISPLAY 0.638298 (-1596 2175);
PAINT MONO (-1596 2175);
FORCEPROP 2 LAST $XR0 12 
J 0
(-1686 2175);
DISPLAY 0.638298 (-1686 2175);
PAINT MONO (-1686 2175);
FORCEPROP 2 LAST PATH I156
J 0
(-1575 2225);
DISPLAY 1.021277 (-1575 2225);
DISPLAY INVISIBLE (-1575 2225);
FORCEPROP 1 LAST COMMENT_BODY TRUE
J 0
(-1920 2080);
DISPLAY 0.872340 (-1920 2080);
PAINT PEACH (-1920 2080);
DISPLAY INVISIBLE (-1920 2080);
FORCEPROP 1 LAST OFFPAGE TRUE
J 0
(-1550 2050);
DISPLAY 0.872340 (-1550 2050);
PAINT GREEN (-1550 2050);
DISPLAY INVISIBLE (-1550 2050);
FORCEPROP 2 LAST CDS_LIB standard
J 0
(-1875 2175);
DISPLAY INVISIBLE (-1875 2175);
FORCEADD OFFPAGE..5
R 2
(4450 -1100);
FORCEPROP 2 LAST $XR0 13 
J 0
(4729 -1100);
DISPLAY 0.638298 (4729 -1100);
PAINT MONO (4729 -1100);
FORCEPROP 2 LAST $XR1 46 
J 0
(4729 -1136);
DISPLAY 0.638298 (4729 -1136);
PAINT MONO (4729 -1136);
FORCEPROP 2 LAST PATH I158
J 0
(4625 -1025);
DISPLAY 1.021277 (4625 -1025);
DISPLAY INVISIBLE (4625 -1025);
FORCEPROP 1 LAST COMMENT_BODY TRUE
J 2
(4350 -1175);
DISPLAY 0.872340 (4350 -1175);
PAINT PEACH (4350 -1175);
DISPLAY INVISIBLE (4350 -1175);
FORCEPROP 1 LAST OFFPAGE TRUE
J 2
(4125 -1225);
DISPLAY 0.872340 (4125 -1225);
PAINT GREEN (4125 -1225);
DISPLAY INVISIBLE (4125 -1225);
FORCEPROP 2 LAST CDS_LIB standard
J 0
(4450 -1100);
DISPLAY INVISIBLE (4450 -1100);
FORCEADD VCCAUX15..1
(2375 -100);
FORCEPROP 3 LASTPIN (2375 -150) SIG_NAME P3V3_AUX\g
J 0
(2385 -140);
DISPLAY 0.659574 (2385 -140);
PAINT MONO (2385 -140);
DISPLAY INVISIBLE (2385 -140);
FORCEPROP 1 LAST HDL_POWER P3V3_AUX
J 1
(2375 -50);
DISPLAY 0.702128 (2375 -50);
PAINT GREEN (2375 -50);
FORCEPROP 1 LAST PATH I160
J 0
(2425 -75);
DISPLAY 0.872340 (2425 -75);
PAINT AQUA (2425 -75);
DISPLAY INVISIBLE (2425 -75);
FORCEPROP 2 LAST CDS_LIB logical_power
J 0
(2375 -100);
DISPLAY INVISIBLE (2375 -100);
FORCEADD OFFPAGE..1
(1525 -675);
FORCEPROP 2 LAST $XR2 17 
J 0
(1124 -675);
DISPLAY 0.638298 (1124 -675);
PAINT MONO (1124 -675);
FORCEPROP 2 LAST $XR1 11 
J 0
(1214 -675);
DISPLAY 0.638298 (1214 -675);
PAINT MONO (1214 -675);
FORCEPROP 2 LAST $XR0 10 
J 0
(1304 -675);
DISPLAY 0.638298 (1304 -675);
PAINT MONO (1304 -675);
FORCEPROP 2 LAST PATH I161
J 0
(1700 -600);
DISPLAY 1.021277 (1700 -600);
DISPLAY INVISIBLE (1700 -600);
FORCEPROP 1 LAST COMMENT_BODY TRUE
J 0
(1650 -775);
DISPLAY 0.872340 (1650 -775);
PAINT PEACH (1650 -775);
DISPLAY INVISIBLE (1650 -775);
FORCEPROP 1 LAST OFFPAGE TRUE
J 0
(1850 -800);
DISPLAY 0.872340 (1850 -800);
PAINT GREEN (1850 -800);
DISPLAY INVISIBLE (1850 -800);
FORCEPROP 2 LAST CDS_LIB standard
J 0
(1525 -675);
DISPLAY INVISIBLE (1525 -675);
FORCEADD OFFPAGE..5
R 2
(3975 500);
FORCEPROP 2 LAST $XR1 21 
J 0
(4254 500);
DISPLAY 0.638298 (4254 500);
PAINT MONO (4254 500);
FORCEPROP 2 LAST $XR0 13 
J 0
(4164 500);
DISPLAY 0.638298 (4164 500);
PAINT MONO (4164 500);
FORCEPROP 2 LAST PATH I162
J 0
(4275 550);
DISPLAY 1.021277 (4275 550);
DISPLAY INVISIBLE (4275 550);
FORCEPROP 1 LAST COMMENT_BODY TRUE
J 2
(3875 425);
DISPLAY 0.872340 (3875 425);
PAINT PEACH (3875 425);
DISPLAY INVISIBLE (3875 425);
FORCEPROP 1 LAST OFFPAGE TRUE
J 2
(3650 375);
DISPLAY 0.872340 (3650 375);
PAINT GREEN (3650 375);
DISPLAY INVISIBLE (3650 375);
FORCEPROP 2 LAST CDS_LIB standard
J 0
(3975 500);
DISPLAY INVISIBLE (3975 500);
FORCEADD Q_RES..1
(2500 500);
FORCEPROP 1 LAST MATERIAL EMPTY
J 0
(2625 500);
DISPLAY 0.510638 (2625 500);
PAINT RED (2625 500);
FORCEPROP 1 LAST VALUE 4.7K
J 2
(2375 500);
DISPLAY 0.510638 (2375 500);
PAINT SKYBLUE (2375 500);
FORCEPROP 1 LAST PART_NUMBER CS24702FB06
J 0
(2450 600);
DISPLAY 0.510638 (2450 600);
PAINT WHITE (2450 600);
DISPLAY INVISIBLE (2450 600);
FORCEPROP 1 LAST PACK_TYPE 0402LF
J 0
(2750 350);
DISPLAY 0.510638 (2750 350);
PAINT SKYBLUE (2750 350);
DISPLAY INVISIBLE (2750 350);
FORCEPROP 1 LAST WATTAGE 1/16W
J 2
(2475 350);
DISPLAY 0.510638 (2475 350);
PAINT SKYBLUE (2475 350);
DISPLAY INVISIBLE (2475 350);
FORCEPROP 1 LAST PATH I163
J 0
(2450 650);
DISPLAY 0.978723 (2450 650);
PAINT WHITE (2450 650);
DISPLAY INVISIBLE (2450 650);
FORCEPROP 1 LAST TOLERANCE 1%
J 0
(2500 400);
DISPLAY 0.510638 (2500 400);
PAINT SKYBLUE (2500 400);
DISPLAY INVISIBLE (2500 400);
FORCEPROP 2 LAST CDS_LIB pure_quanta
J 0
(2500 500);
DISPLAY INVISIBLE (2500 500);
FORCEPROP 1 LAST LOCATION R699
J 0
(2150 500);
DISPLAY 0.702128 (2150 500);
PAINT YELLOW (2150 500);
FORCEPROP 0 LAST $SEC 1
J 0
(2150 550);
DISPLAY INVISIBLE (2150 550);
FORCEPROP 0 LAST CDS_SEC 1
J 0
(2150 550);
DISPLAY INVISIBLE (2150 550);
FORCEPROP 1 LASTPIN (2400 500) $PN 1
J 0
(2412 512);
DISPLAY 0.808511 (2412 512);
PAINT WHITE (2412 512);
DISPLAY INVISIBLE (2412 512);
FORCEPROP 1 LASTPIN (2600 500) $PN 2
J 0
(2562 512);
DISPLAY 0.808511 (2562 512);
PAINT WHITE (2562 512);
DISPLAY INVISIBLE (2562 512);
FORCEADD VCCAUX15..1
(2100 750);
FORCEPROP 3 LASTPIN (2100 700) SIG_NAME P3V3_AUX\g
J 0
(2110 710);
DISPLAY 0.659574 (2110 710);
PAINT MONO (2110 710);
DISPLAY INVISIBLE (2110 710);
FORCEPROP 1 LAST HDL_POWER P3V3_AUX
J 1
(2100 800);
DISPLAY 0.702128 (2100 800);
PAINT GREEN (2100 800);
FORCEPROP 1 LAST PATH I164
J 0
(2150 775);
DISPLAY 0.872340 (2150 775);
PAINT AQUA (2150 775);
DISPLAY INVISIBLE (2150 775);
FORCEPROP 2 LAST CDS_LIB logical_power
J 0
(2100 750);
DISPLAY INVISIBLE (2100 750);
FORCEADD Q_RES..1
(2225 -675);
FORCEPROP 1 LAST MATERIAL CHIP
J 0
(2300 -750);
DISPLAY 0.510638 (2300 -750);
PAINT SKYBLUE (2300 -750);
FORCEPROP 1 LAST TOLERANCE 1%
J 0
(2225 -750);
DISPLAY 0.510638 (2225 -750);
PAINT SKYBLUE (2225 -750);
FORCEPROP 1 LAST VALUE 2K
J 2
(2200 -750);
DISPLAY 0.510638 (2200 -750);
PAINT SKYBLUE (2200 -750);
FORCEPROP 1 LAST WATTAGE 1/16W
J 2
(2125 -750);
DISPLAY 0.510638 (2125 -750);
PAINT SKYBLUE (2125 -750);
FORCEPROP 1 LAST PACK_TYPE 0402LF
J 0
(2425 -750);
DISPLAY 0.510638 (2425 -750);
PAINT SKYBLUE (2425 -750);
FORCEPROP 1 LAST PART_NUMBER CS22002FB07
J 0
(2300 -650);
DISPLAY 0.510638 (2300 -650);
PAINT WHITE (2300 -650);
DISPLAY INVISIBLE (2300 -650);
FORCEPROP 1 LAST PATH I165
J 0
(2175 -525);
DISPLAY 0.978723 (2175 -525);
PAINT WHITE (2175 -525);
DISPLAY INVISIBLE (2175 -525);
FORCEPROP 2 LAST CDS_LIB pure_quanta
J 0
(2225 -675);
DISPLAY INVISIBLE (2225 -675);
FORCEPROP 1 LAST LOCATION R714
J 0
(2075 -650);
DISPLAY 0.702128 (2075 -650);
PAINT YELLOW (2075 -650);
FORCEPROP 0 LAST $SEC 1
J 0
(2075 -600);
DISPLAY INVISIBLE (2075 -600);
FORCEPROP 0 LAST CDS_SEC 1
J 0
(2075 -600);
DISPLAY INVISIBLE (2075 -600);
FORCEPROP 1 LASTPIN (2125 -675) $PN 1
J 0
(2137 -663);
DISPLAY 0.808511 (2137 -663);
PAINT WHITE (2137 -663);
DISPLAY INVISIBLE (2137 -663);
FORCEPROP 1 LASTPIN (2325 -675) $PN 2
J 0
(2287 -663);
DISPLAY 0.808511 (2287 -663);
PAINT WHITE (2287 -663);
DISPLAY INVISIBLE (2287 -663);
FORCEADD Q_CAP..1
(2650 -900);
FORCEPROP 1 LAST TOLERANCE 10%
J 0
(2700 -950);
DISPLAY 0.510638 (2700 -950);
PAINT SKYBLUE (2700 -950);
FORCEPROP 1 LAST PACK_TYPE 0402
J 0
(2700 -1100);
DISPLAY 0.510638 (2700 -1100);
PAINT SKYBLUE (2700 -1100);
FORCEPROP 1 LAST VOLTAGE 16V
J 0
(2700 -900);
DISPLAY 0.510638 (2700 -900);
PAINT SKYBLUE (2700 -900);
FORCEPROP 1 LAST VALUE 1UF
J 0
(2700 -850);
DISPLAY 0.510638 (2700 -850);
PAINT SKYBLUE (2700 -850);
FORCEPROP 1 LAST PART_NUMBER TMP_QCH5103K9B00
J 0
(2700 -1050);
DISPLAY 0.510638 (2700 -1050);
PAINT WHITE (2700 -1050);
FORCEPROP 1 LAST MATERIAL EMPTY
J 0
(2700 -1000);
DISPLAY 0.510638 (2700 -1000);
PAINT RED (2700 -1000);
FORCEPROP 1 LAST PATH I166
J 0
(2700 -750);
DISPLAY 0.978723 (2700 -750);
PAINT WHITE (2700 -750);
DISPLAY INVISIBLE (2700 -750);
FORCEPROP 2 LAST CDS_LIB pure_quanta
J 0
(2650 -900);
DISPLAY INVISIBLE (2650 -900);
FORCEPROP 1 LAST LOCATION C267
J 0
(2700 -800);
DISPLAY 0.702128 (2700 -800);
PAINT YELLOW (2700 -800);
FORCEPROP 1 LASTPIN (2650 -800) $PN 1
J 0
(2660 -820);
DISPLAY 0.808511 (2660 -820);
PAINT WHITE (2660 -820);
FORCEPROP 1 LASTPIN (2650 -1000) $PN 2
J 0
(2660 -1020);
DISPLAY 0.808511 (2660 -1020);
PAINT WHITE (2660 -1020);
FORCEPROP 0 LAST $SEC 1
J 0
(2700 -750);
DISPLAY 0.680851 (2700 -750);
PAINT MONO (2700 -750);
DISPLAY INVISIBLE (2700 -750);
FORCEPROP 0 LAST CDS_SEC 1
J 0
(2700 -750);
DISPLAY 1.021277 (2700 -750);
DISPLAY INVISIBLE (2700 -750);
FORCEADD UNIVERSAL_GND..1
(2650 -1125);
FORCEPROP 3 LASTPIN (2650 -1075) SIG_NAME GND\g
J 0
(2660 -1065);
DISPLAY 0.659574 (2660 -1065);
PAINT MONO (2660 -1065);
DISPLAY INVISIBLE (2660 -1065);
FORCEPROP 1 LAST PATH I167
J 0
(2725 -1125);
DISPLAY 0.872340 (2725 -1125);
PAINT AQUA (2725 -1125);
DISPLAY INVISIBLE (2725 -1125);
FORCEPROP 1 LAST HDL_POWER GND
J 1
(2675 -1200);
DISPLAY 0.702128 (2675 -1200);
PAINT GREEN (2675 -1200);
DISPLAY INVISIBLE (2675 -1200);
FORCEPROP 2 LAST CDS_LIB logical_power
J 0
(2650 -1125);
DISPLAY INVISIBLE (2650 -1125);
FORCEADD Q_RES..1
(-3625 1050);
FORCEPROP 1 LAST VALUE 4.7K
J 2
(-3750 1050);
DISPLAY 0.510638 (-3750 1050);
PAINT SKYBLUE (-3750 1050);
FORCEPROP 1 LAST MATERIAL CHIP
J 0
(-3500 1050);
DISPLAY 0.510638 (-3500 1050);
PAINT SKYBLUE (-3500 1050);
FORCEPROP 1 LAST PART_NUMBER CS24702FB06
J 0
(-3675 1150);
DISPLAY 0.510638 (-3675 1150);
PAINT WHITE (-3675 1150);
DISPLAY INVISIBLE (-3675 1150);
FORCEPROP 1 LAST PACK_TYPE 0402LF
J 0
(-3375 900);
DISPLAY 0.510638 (-3375 900);
PAINT SKYBLUE (-3375 900);
DISPLAY INVISIBLE (-3375 900);
FORCEPROP 1 LAST WATTAGE 1/16W
J 2
(-3650 900);
DISPLAY 0.510638 (-3650 900);
PAINT SKYBLUE (-3650 900);
DISPLAY INVISIBLE (-3650 900);
FORCEPROP 1 LAST PATH I168
J 0
(-3675 1200);
DISPLAY 0.978723 (-3675 1200);
PAINT WHITE (-3675 1200);
DISPLAY INVISIBLE (-3675 1200);
FORCEPROP 1 LAST TOLERANCE 1%
J 0
(-3625 950);
DISPLAY 0.510638 (-3625 950);
PAINT SKYBLUE (-3625 950);
DISPLAY INVISIBLE (-3625 950);
FORCEPROP 2 LAST CDS_LIB pure_quanta
J 0
(-3625 1050);
DISPLAY INVISIBLE (-3625 1050);
FORCEPROP 1 LAST LOCATION R842
J 0
(-3975 1050);
DISPLAY 0.702128 (-3975 1050);
PAINT YELLOW (-3975 1050);
FORCEPROP 0 LAST $SEC 1
J 0
(-3900 1100);
DISPLAY INVISIBLE (-3900 1100);
FORCEPROP 0 LAST CDS_SEC 1
J 0
(-3900 1100);
DISPLAY INVISIBLE (-3900 1100);
FORCEPROP 1 LASTPIN (-3725 1050) $PN 1
J 0
(-3713 1062);
DISPLAY 0.808511 (-3713 1062);
PAINT WHITE (-3713 1062);
DISPLAY INVISIBLE (-3713 1062);
FORCEPROP 1 LASTPIN (-3525 1050) $PN 2
J 0
(-3563 1062);
DISPLAY 0.808511 (-3563 1062);
PAINT WHITE (-3563 1062);
DISPLAY INVISIBLE (-3563 1062);
FORCEADD OFFPAGE..2
(-2525 975);
FORCEPROP 2 LAST $XR0 15 
J 0
(-2336 975);
DISPLAY 0.638298 (-2336 975);
PAINT MONO (-2336 975);
FORCEPROP 2 LAST $XR1 35 
J 0
(-2246 975);
DISPLAY 0.638298 (-2246 975);
PAINT MONO (-2246 975);
FORCEPROP 2 LAST PATH I169
J 0
(-2325 1025);
DISPLAY 1.021277 (-2325 1025);
DISPLAY INVISIBLE (-2325 1025);
FORCEPROP 1 LAST COMMENT_BODY TRUE
J 0
(-2570 880);
DISPLAY 0.872340 (-2570 880);
PAINT PEACH (-2570 880);
DISPLAY INVISIBLE (-2570 880);
FORCEPROP 1 LAST OFFPAGE TRUE
J 0
(-2200 850);
DISPLAY 0.872340 (-2200 850);
PAINT GREEN (-2200 850);
DISPLAY INVISIBLE (-2200 850);
FORCEPROP 2 LAST CDS_LIB standard
J 0
(-2525 975);
DISPLAY INVISIBLE (-2525 975);
FORCEADD OFFPAGE..2
(-2525 1050);
FORCEPROP 2 LAST $XR1 35 
J 0
(-2246 1050);
DISPLAY 0.638298 (-2246 1050);
PAINT MONO (-2246 1050);
FORCEPROP 2 LAST $XR0 15 
J 0
(-2336 1050);
DISPLAY 0.638298 (-2336 1050);
PAINT MONO (-2336 1050);
FORCEPROP 2 LAST PATH I170
J 0
(-2325 1100);
DISPLAY 1.021277 (-2325 1100);
DISPLAY INVISIBLE (-2325 1100);
FORCEPROP 1 LAST COMMENT_BODY TRUE
J 0
(-2570 955);
DISPLAY 0.872340 (-2570 955);
PAINT PEACH (-2570 955);
DISPLAY INVISIBLE (-2570 955);
FORCEPROP 1 LAST OFFPAGE TRUE
J 0
(-2200 925);
DISPLAY 0.872340 (-2200 925);
PAINT GREEN (-2200 925);
DISPLAY INVISIBLE (-2200 925);
FORCEPROP 2 LAST CDS_LIB standard
J 0
(-2525 1050);
DISPLAY INVISIBLE (-2525 1050);
FORCEADD OFFPAGE..2
(-2525 825);
FORCEPROP 2 LAST $XR0 35 
J 0
(-2336 825);
DISPLAY 0.638298 (-2336 825);
PAINT MONO (-2336 825);
FORCEPROP 2 LAST $XR1 15 
J 0
(-2246 825);
DISPLAY 0.638298 (-2246 825);
PAINT MONO (-2246 825);
FORCEPROP 2 LAST PATH I173
J 0
(-2325 875);
DISPLAY 1.021277 (-2325 875);
DISPLAY INVISIBLE (-2325 875);
FORCEPROP 1 LAST COMMENT_BODY TRUE
J 0
(-2570 730);
DISPLAY 0.872340 (-2570 730);
PAINT PEACH (-2570 730);
DISPLAY INVISIBLE (-2570 730);
FORCEPROP 1 LAST OFFPAGE TRUE
J 0
(-2200 700);
DISPLAY 0.872340 (-2200 700);
PAINT GREEN (-2200 700);
DISPLAY INVISIBLE (-2200 700);
FORCEPROP 2 LAST CDS_LIB standard
J 0
(-2525 825);
DISPLAY INVISIBLE (-2525 825);
FORCEADD OFFPAGE..2
(-2525 675);
FORCEPROP 2 LAST $XR1 15 
J 0
(-2246 675);
DISPLAY 0.638298 (-2246 675);
PAINT MONO (-2246 675);
FORCEPROP 2 LAST $XR0 35 
J 0
(-2336 675);
DISPLAY 0.638298 (-2336 675);
PAINT MONO (-2336 675);
FORCEPROP 2 LAST PATH I174
J 0
(-2325 725);
DISPLAY 1.021277 (-2325 725);
DISPLAY INVISIBLE (-2325 725);
FORCEPROP 1 LAST COMMENT_BODY TRUE
J 0
(-2570 580);
DISPLAY 0.872340 (-2570 580);
PAINT PEACH (-2570 580);
DISPLAY INVISIBLE (-2570 580);
FORCEPROP 1 LAST OFFPAGE TRUE
J 0
(-2200 550);
DISPLAY 0.872340 (-2200 550);
PAINT GREEN (-2200 550);
DISPLAY INVISIBLE (-2200 550);
FORCEPROP 2 LAST CDS_LIB standard
J 0
(-2525 675);
DISPLAY INVISIBLE (-2525 675);
FORCEADD OFFPAGE..2
(-2525 525);
FORCEPROP 2 LAST $XR2 35 
J 0
(-2156 525);
DISPLAY 0.638298 (-2156 525);
PAINT MONO (-2156 525);
FORCEPROP 2 LAST $XR1 26 
J 0
(-2246 525);
DISPLAY 0.638298 (-2246 525);
PAINT MONO (-2246 525);
FORCEPROP 2 LAST $XR0 15 
J 0
(-2336 525);
DISPLAY 0.638298 (-2336 525);
PAINT MONO (-2336 525);
FORCEPROP 2 LAST PATH I175
J 0
(-2325 575);
DISPLAY 1.021277 (-2325 575);
DISPLAY INVISIBLE (-2325 575);
FORCEPROP 1 LAST COMMENT_BODY TRUE
J 0
(-2570 430);
DISPLAY 0.872340 (-2570 430);
PAINT PEACH (-2570 430);
DISPLAY INVISIBLE (-2570 430);
FORCEPROP 1 LAST OFFPAGE TRUE
J 0
(-2200 400);
DISPLAY 0.872340 (-2200 400);
PAINT GREEN (-2200 400);
DISPLAY INVISIBLE (-2200 400);
FORCEPROP 2 LAST CDS_LIB standard
J 0
(-2525 525);
DISPLAY INVISIBLE (-2525 525);
FORCEADD Q_RES..1
(-3625 975);
FORCEPROP 1 LAST VALUE 4.7K
J 2
(-3750 975);
DISPLAY 0.510638 (-3750 975);
PAINT SKYBLUE (-3750 975);
FORCEPROP 1 LAST MATERIAL CHIP
J 0
(-3500 975);
DISPLAY 0.510638 (-3500 975);
PAINT SKYBLUE (-3500 975);
FORCEPROP 1 LAST PART_NUMBER CS24702FB06
J 0
(-3675 1075);
DISPLAY 0.510638 (-3675 1075);
PAINT WHITE (-3675 1075);
DISPLAY INVISIBLE (-3675 1075);
FORCEPROP 1 LAST PACK_TYPE 0402LF
J 0
(-3375 825);
DISPLAY 0.510638 (-3375 825);
PAINT SKYBLUE (-3375 825);
DISPLAY INVISIBLE (-3375 825);
FORCEPROP 1 LAST WATTAGE 1/16W
J 2
(-3650 825);
DISPLAY 0.510638 (-3650 825);
PAINT SKYBLUE (-3650 825);
DISPLAY INVISIBLE (-3650 825);
FORCEPROP 1 LAST PATH I177
J 0
(-3675 1125);
DISPLAY 0.978723 (-3675 1125);
PAINT WHITE (-3675 1125);
DISPLAY INVISIBLE (-3675 1125);
FORCEPROP 1 LAST TOLERANCE 1%
J 0
(-3625 875);
DISPLAY 0.510638 (-3625 875);
PAINT SKYBLUE (-3625 875);
DISPLAY INVISIBLE (-3625 875);
FORCEPROP 2 LAST CDS_LIB pure_quanta
J 0
(-3625 975);
DISPLAY INVISIBLE (-3625 975);
FORCEPROP 1 LAST LOCATION R843
J 0
(-3975 975);
DISPLAY 0.702128 (-3975 975);
PAINT YELLOW (-3975 975);
FORCEPROP 0 LAST $SEC 1
J 0
(-3900 1025);
DISPLAY INVISIBLE (-3900 1025);
FORCEPROP 0 LAST CDS_SEC 1
J 0
(-3900 1025);
DISPLAY INVISIBLE (-3900 1025);
FORCEPROP 1 LASTPIN (-3725 975) $PN 1
J 0
(-3713 987);
DISPLAY 0.808511 (-3713 987);
PAINT WHITE (-3713 987);
DISPLAY INVISIBLE (-3713 987);
FORCEPROP 1 LASTPIN (-3525 975) $PN 2
J 0
(-3563 987);
DISPLAY 0.808511 (-3563 987);
PAINT WHITE (-3563 987);
DISPLAY INVISIBLE (-3563 987);
FORCEADD Q_RES..1
(-3625 825);
FORCEPROP 1 LAST VALUE 4.7K
J 2
(-3750 825);
DISPLAY 0.510638 (-3750 825);
PAINT SKYBLUE (-3750 825);
FORCEPROP 1 LAST MATERIAL CHIP
J 0
(-3500 825);
DISPLAY 0.510638 (-3500 825);
PAINT SKYBLUE (-3500 825);
FORCEPROP 1 LAST PART_NUMBER CS24702FB06
J 0
(-3675 925);
DISPLAY 0.510638 (-3675 925);
PAINT WHITE (-3675 925);
DISPLAY INVISIBLE (-3675 925);
FORCEPROP 1 LAST PACK_TYPE 0402LF
J 0
(-3375 675);
DISPLAY 0.510638 (-3375 675);
PAINT SKYBLUE (-3375 675);
DISPLAY INVISIBLE (-3375 675);
FORCEPROP 1 LAST WATTAGE 1/16W
J 2
(-3650 675);
DISPLAY 0.510638 (-3650 675);
PAINT SKYBLUE (-3650 675);
DISPLAY INVISIBLE (-3650 675);
FORCEPROP 1 LAST PATH I179
J 0
(-3675 975);
DISPLAY 0.978723 (-3675 975);
PAINT WHITE (-3675 975);
DISPLAY INVISIBLE (-3675 975);
FORCEPROP 1 LAST TOLERANCE 1%
J 0
(-3625 725);
DISPLAY 0.510638 (-3625 725);
PAINT SKYBLUE (-3625 725);
DISPLAY INVISIBLE (-3625 725);
FORCEPROP 2 LAST CDS_LIB pure_quanta
J 0
(-3625 825);
DISPLAY INVISIBLE (-3625 825);
FORCEPROP 1 LAST LOCATION R844
J 0
(-3975 825);
DISPLAY 0.702128 (-3975 825);
PAINT YELLOW (-3975 825);
FORCEPROP 0 LAST $SEC 1
J 0
(-3900 875);
DISPLAY INVISIBLE (-3900 875);
FORCEPROP 0 LAST CDS_SEC 1
J 0
(-3900 875);
DISPLAY INVISIBLE (-3900 875);
FORCEPROP 1 LASTPIN (-3725 825) $PN 1
J 0
(-3713 837);
DISPLAY 0.808511 (-3713 837);
PAINT WHITE (-3713 837);
DISPLAY INVISIBLE (-3713 837);
FORCEPROP 1 LASTPIN (-3525 825) $PN 2
J 0
(-3563 837);
DISPLAY 0.808511 (-3563 837);
PAINT WHITE (-3563 837);
DISPLAY INVISIBLE (-3563 837);
FORCEADD Q_RES..1
(-3625 675);
FORCEPROP 1 LAST VALUE 4.7K
J 2
(-3750 675);
DISPLAY 0.510638 (-3750 675);
PAINT SKYBLUE (-3750 675);
FORCEPROP 1 LAST MATERIAL EMPTY
J 0
(-3500 675);
DISPLAY 0.510638 (-3500 675);
PAINT RED (-3500 675);
FORCEPROP 1 LAST PART_NUMBER CS24702FB06
J 0
(-3675 775);
DISPLAY 0.510638 (-3675 775);
PAINT WHITE (-3675 775);
DISPLAY INVISIBLE (-3675 775);
FORCEPROP 1 LAST PACK_TYPE 0402LF
J 0
(-3375 525);
DISPLAY 0.510638 (-3375 525);
PAINT SKYBLUE (-3375 525);
DISPLAY INVISIBLE (-3375 525);
FORCEPROP 1 LAST WATTAGE 1/16W
J 2
(-3650 525);
DISPLAY 0.510638 (-3650 525);
PAINT SKYBLUE (-3650 525);
DISPLAY INVISIBLE (-3650 525);
FORCEPROP 1 LAST PATH I181
J 0
(-3675 825);
DISPLAY 0.978723 (-3675 825);
PAINT WHITE (-3675 825);
DISPLAY INVISIBLE (-3675 825);
FORCEPROP 1 LAST TOLERANCE 1%
J 0
(-3625 575);
DISPLAY 0.510638 (-3625 575);
PAINT SKYBLUE (-3625 575);
DISPLAY INVISIBLE (-3625 575);
FORCEPROP 2 LAST CDS_LIB pure_quanta
J 0
(-3625 675);
DISPLAY INVISIBLE (-3625 675);
FORCEPROP 1 LAST LOCATION R846
J 0
(-3975 675);
DISPLAY 0.702128 (-3975 675);
PAINT YELLOW (-3975 675);
FORCEPROP 0 LAST $SEC 1
J 0
(-3900 725);
DISPLAY INVISIBLE (-3900 725);
FORCEPROP 0 LAST CDS_SEC 1
J 0
(-3900 725);
DISPLAY INVISIBLE (-3900 725);
FORCEPROP 1 LASTPIN (-3725 675) $PN 1
J 0
(-3713 687);
DISPLAY 0.808511 (-3713 687);
PAINT WHITE (-3713 687);
DISPLAY INVISIBLE (-3713 687);
FORCEPROP 1 LASTPIN (-3525 675) $PN 2
J 0
(-3563 687);
DISPLAY 0.808511 (-3563 687);
PAINT WHITE (-3563 687);
DISPLAY INVISIBLE (-3563 687);
FORCEADD Q_RES..1
(-3625 525);
FORCEPROP 1 LAST VALUE 4.7K
J 2
(-3750 525);
DISPLAY 0.510638 (-3750 525);
PAINT SKYBLUE (-3750 525);
FORCEPROP 1 LAST MATERIAL CHIP
J 0
(-3500 525);
DISPLAY 0.510638 (-3500 525);
PAINT SKYBLUE (-3500 525);
FORCEPROP 1 LAST PART_NUMBER CS24702FB06
J 0
(-3675 625);
DISPLAY 0.510638 (-3675 625);
PAINT WHITE (-3675 625);
DISPLAY INVISIBLE (-3675 625);
FORCEPROP 1 LAST PACK_TYPE 0402LF
J 0
(-3375 375);
DISPLAY 0.510638 (-3375 375);
PAINT SKYBLUE (-3375 375);
DISPLAY INVISIBLE (-3375 375);
FORCEPROP 1 LAST WATTAGE 1/16W
J 2
(-3650 375);
DISPLAY 0.510638 (-3650 375);
PAINT SKYBLUE (-3650 375);
DISPLAY INVISIBLE (-3650 375);
FORCEPROP 1 LAST PATH I182
J 0
(-3675 675);
DISPLAY 0.978723 (-3675 675);
PAINT WHITE (-3675 675);
DISPLAY INVISIBLE (-3675 675);
FORCEPROP 1 LAST TOLERANCE 1%
J 0
(-3625 425);
DISPLAY 0.510638 (-3625 425);
PAINT SKYBLUE (-3625 425);
DISPLAY INVISIBLE (-3625 425);
FORCEPROP 2 LAST CDS_LIB pure_quanta
J 0
(-3625 525);
DISPLAY INVISIBLE (-3625 525);
FORCEPROP 1 LAST LOCATION R848
J 0
(-3975 525);
DISPLAY 0.702128 (-3975 525);
PAINT YELLOW (-3975 525);
FORCEPROP 0 LAST $SEC 1
J 0
(-3900 575);
DISPLAY INVISIBLE (-3900 575);
FORCEPROP 0 LAST CDS_SEC 1
J 0
(-3900 575);
DISPLAY INVISIBLE (-3900 575);
FORCEPROP 1 LASTPIN (-3725 525) $PN 1
J 0
(-3713 537);
DISPLAY 0.808511 (-3713 537);
PAINT WHITE (-3713 537);
DISPLAY INVISIBLE (-3713 537);
FORCEPROP 1 LASTPIN (-3525 525) $PN 2
J 0
(-3563 537);
DISPLAY 0.808511 (-3563 537);
PAINT WHITE (-3563 537);
DISPLAY INVISIBLE (-3563 537);
FORCEADD OFFPAGE..2
(-2525 600);
FORCEPROP 2 LAST $XR0 12 
J 0
(-2336 600);
DISPLAY 0.638298 (-2336 600);
PAINT MONO (-2336 600);
FORCEPROP 2 LAST PATH I183
J 0
(-2225 650);
DISPLAY 1.021277 (-2225 650);
DISPLAY INVISIBLE (-2225 650);
FORCEPROP 1 LAST COMMENT_BODY TRUE
J 0
(-2570 505);
DISPLAY 0.872340 (-2570 505);
PAINT PEACH (-2570 505);
DISPLAY INVISIBLE (-2570 505);
FORCEPROP 1 LAST OFFPAGE TRUE
J 0
(-2200 475);
DISPLAY 0.872340 (-2200 475);
PAINT GREEN (-2200 475);
DISPLAY INVISIBLE (-2200 475);
FORCEPROP 2 LAST CDS_LIB standard
J 0
(-2525 600);
DISPLAY INVISIBLE (-2525 600);
FORCEADD Q_RES..1
(-3625 600);
FORCEPROP 1 LAST VALUE 4.7K
J 2
(-3750 600);
DISPLAY 0.510638 (-3750 600);
PAINT SKYBLUE (-3750 600);
FORCEPROP 1 LAST MATERIAL CHIP
J 0
(-3500 600);
DISPLAY 0.510638 (-3500 600);
PAINT SKYBLUE (-3500 600);
FORCEPROP 1 LAST PART_NUMBER CS24702FB06
J 0
(-3675 700);
DISPLAY 0.510638 (-3675 700);
PAINT WHITE (-3675 700);
DISPLAY INVISIBLE (-3675 700);
FORCEPROP 1 LAST PACK_TYPE 0402LF
J 0
(-3375 450);
DISPLAY 0.510638 (-3375 450);
PAINT SKYBLUE (-3375 450);
DISPLAY INVISIBLE (-3375 450);
FORCEPROP 1 LAST WATTAGE 1/16W
J 2
(-3650 450);
DISPLAY 0.510638 (-3650 450);
PAINT SKYBLUE (-3650 450);
DISPLAY INVISIBLE (-3650 450);
FORCEPROP 1 LAST PATH I184
J 0
(-3675 750);
DISPLAY 0.978723 (-3675 750);
PAINT WHITE (-3675 750);
DISPLAY INVISIBLE (-3675 750);
FORCEPROP 1 LAST TOLERANCE 1%
J 0
(-3625 500);
DISPLAY 0.510638 (-3625 500);
PAINT SKYBLUE (-3625 500);
DISPLAY INVISIBLE (-3625 500);
FORCEPROP 2 LAST CDS_LIB pure_quanta
J 0
(-3625 600);
DISPLAY INVISIBLE (-3625 600);
FORCEPROP 1 LAST LOCATION R851
J 0
(-3975 600);
DISPLAY 0.702128 (-3975 600);
PAINT YELLOW (-3975 600);
FORCEPROP 0 LAST $SEC 1
J 0
(-3900 650);
DISPLAY INVISIBLE (-3900 650);
FORCEPROP 0 LAST CDS_SEC 1
J 0
(-3900 650);
DISPLAY INVISIBLE (-3900 650);
FORCEPROP 1 LASTPIN (-3725 600) $PN 1
J 0
(-3713 612);
DISPLAY 0.808511 (-3713 612);
PAINT WHITE (-3713 612);
DISPLAY INVISIBLE (-3713 612);
FORCEPROP 1 LASTPIN (-3525 600) $PN 2
J 0
(-3563 612);
DISPLAY 0.808511 (-3563 612);
PAINT WHITE (-3563 612);
DISPLAY INVISIBLE (-3563 612);
FORCEADD BAT54C..1
R 6
(2800 2150);
FORCEPROP 1 LAST PART_NUMBER BCBAT54CZ04
J 0
(2900 2156);
DISPLAY 0.510638 (2900 2156);
PAINT WHITE (2900 2156);
FORCEPROP 1 LAST MATERIAL IC
J 0
(2900 2206);
DISPLAY 0.510638 (2900 2206);
PAINT SKYBLUE (2900 2206);
FORCEPROP 2 LAST PART_TYPE SMLF
J 0
(2900 2002);
DISPLAY 0.510638 (2900 2002);
PAINT SKYBLUE (2900 2002);
FORCEPROP 2 LAST VALUE BAT54C
J 0
(2900 2052);
DISPLAY 0.510638 (2900 2052);
PAINT SKYBLUE (2900 2052);
FORCEPROP 1 LAST PATH I185
J 0
(2975 2211);
DISPLAY 0.723404 (2975 2211);
PAINT GREEN (2975 2211);
DISPLAY INVISIBLE (2975 2211);
FORCEPROP 1 LAST NEEDS_NO_SIZE TRUE
J 0
(2800 2128);
DISPLAY 0.468085 (2800 2128);
PAINT GREEN (2800 2128);
DISPLAY INVISIBLE (2800 2128);
FORCEPROP 2 LAST CDS_LIB pure_quanta
J 0
(2800 2103);
DISPLAY INVISIBLE (2800 2103);
FORCEPROP 1 LAST LOCATION U11
J 0
(2900 2111);
DISPLAY 0.702128 (2900 2111);
PAINT YELLOW (2900 2111);
FORCEPROP 0 LASTPIN (2850 2250) $PN 2
R 1
J 0
(2840 2260);
DISPLAY 0.680851 (2840 2260);
PAINT MONO (2840 2260);
FORCEPROP 0 LASTPIN (2750 2250) $PN 1
R 1
J 0
(2740 2260);
DISPLAY 0.680851 (2740 2260);
PAINT MONO (2740 2260);
FORCEPROP 0 LASTPIN (2800 2050) $PN 3
R 1
J 2
(2790 2040);
DISPLAY 0.680851 (2790 2040);
PAINT MONO (2790 2040);
FORCEPROP 0 LAST $SEC 1
J 0
(2900 2250);
DISPLAY 0.680851 (2900 2250);
PAINT MONO (2900 2250);
DISPLAY INVISIBLE (2900 2250);
FORCEPROP 0 LAST CDS_SEC 1
J 0
(2900 2250);
DISPLAY 1.021277 (2900 2250);
DISPLAY INVISIBLE (2900 2250);
FORCEADD OFFPAGE..2
(3725 2300);
FORCEPROP 2 LAST $XR2 30 
J 0
(4094 2300);
DISPLAY 0.638298 (4094 2300);
PAINT MONO (4094 2300);
FORCEPROP 2 LAST $XR0 13 
J 0
(3914 2300);
DISPLAY 0.638298 (3914 2300);
PAINT MONO (3914 2300);
FORCEPROP 2 LAST $XR1 27 
J 0
(4004 2300);
DISPLAY 0.638298 (4004 2300);
PAINT MONO (4004 2300);
FORCEPROP 2 LAST PATH I186
J 0
(3925 2350);
DISPLAY 1.021277 (3925 2350);
DISPLAY INVISIBLE (3925 2350);
FORCEPROP 1 LAST COMMENT_BODY TRUE
J 0
(3680 2205);
DISPLAY 0.872340 (3680 2205);
PAINT PEACH (3680 2205);
DISPLAY INVISIBLE (3680 2205);
FORCEPROP 1 LAST OFFPAGE TRUE
J 0
(4050 2175);
DISPLAY 0.872340 (4050 2175);
PAINT GREEN (4050 2175);
DISPLAY INVISIBLE (4050 2175);
FORCEPROP 2 LAST CDS_LIB standard
J 0
(3725 2300);
DISPLAY INVISIBLE (3725 2300);
FORCEADD OFFPAGE..2
(3725 2425);
FORCEPROP 2 LAST $XR0 13 
J 0
(3914 2425);
DISPLAY 0.638298 (3914 2425);
PAINT MONO (3914 2425);
FORCEPROP 2 LAST $XR1 35 
J 0
(4004 2425);
DISPLAY 0.638298 (4004 2425);
PAINT MONO (4004 2425);
FORCEPROP 2 LAST PATH I187
J 0
(4025 2475);
DISPLAY 1.021277 (4025 2475);
DISPLAY INVISIBLE (4025 2475);
FORCEPROP 1 LAST COMMENT_BODY TRUE
J 0
(3680 2330);
DISPLAY 0.872340 (3680 2330);
PAINT PEACH (3680 2330);
DISPLAY INVISIBLE (3680 2330);
FORCEPROP 1 LAST OFFPAGE TRUE
J 0
(4050 2300);
DISPLAY 0.872340 (4050 2300);
PAINT GREEN (4050 2300);
DISPLAY INVISIBLE (4050 2300);
FORCEPROP 2 LAST CDS_LIB standard
J 0
(3725 2425);
DISPLAY INVISIBLE (3725 2425);
FORCEADD Q_RES..2
(2750 2625);
FORCEPROP 1 LAST PACK_TYPE 0402LF
J 0
(2800 2600);
DISPLAY 0.510638 (2800 2600);
PAINT SKYBLUE (2800 2600);
FORCEPROP 1 LAST MATERIAL CHIP
J 0
(2800 2500);
DISPLAY 0.510638 (2800 2500);
PAINT SKYBLUE (2800 2500);
FORCEPROP 1 LAST WATTAGE 1/16W
J 0
(2800 2550);
DISPLAY 0.510638 (2800 2550);
PAINT SKYBLUE (2800 2550);
FORCEPROP 1 LAST TOLERANCE 1%
J 0
(2800 2650);
DISPLAY 0.510638 (2800 2650);
PAINT SKYBLUE (2800 2650);
FORCEPROP 1 LAST VALUE 4.7K
J 0
(2800 2700);
DISPLAY 0.510638 (2800 2700);
PAINT SKYBLUE (2800 2700);
FORCEPROP 1 LAST PART_NUMBER CS24702FB06
J 0
(2795 2500);
DISPLAY 0.510638 (2795 2500);
PAINT WHITE (2795 2500);
DISPLAY INVISIBLE (2795 2500);
FORCEPROP 1 LAST PATH I188
J 0
(2800 2800);
DISPLAY 0.978723 (2800 2800);
PAINT WHITE (2800 2800);
DISPLAY INVISIBLE (2800 2800);
FORCEPROP 2 LAST CDS_LIB pure_quanta
J 0
(2750 2625);
DISPLAY INVISIBLE (2750 2625);
FORCEPROP 1 LAST LOCATION R430
J 0
(2795 2750);
DISPLAY 0.702128 (2795 2750);
PAINT YELLOW (2795 2750);
FORCEPROP 1 LASTPIN (2750 2725) $PN 1
J 0
(2755 2687);
DISPLAY 0.808511 (2755 2687);
PAINT WHITE (2755 2687);
FORCEPROP 1 LASTPIN (2750 2525) $PN 2
J 0
(2755 2535);
DISPLAY 0.808511 (2755 2535);
PAINT WHITE (2755 2535);
FORCEPROP 0 LAST $SEC 1
J 0
(2800 2800);
DISPLAY 0.680851 (2800 2800);
PAINT MONO (2800 2800);
DISPLAY INVISIBLE (2800 2800);
FORCEPROP 0 LAST CDS_SEC 1
J 0
(2800 2800);
DISPLAY 0.680851 (2800 2800);
DISPLAY INVISIBLE (2800 2800);
FORCEADD UNIVERSAL_POWER..1
(2750 2875);
FORCEPROP 3 LASTPIN (2750 2825) SIG_NAME P3V3_AUX\g
J 0
(2760 2835);
DISPLAY 0.659574 (2760 2835);
PAINT MONO (2760 2835);
DISPLAY INVISIBLE (2760 2835);
FORCEPROP 1 LAST HDL_POWER P3V3_AUX
J 1
(2750 2925);
DISPLAY 0.702128 (2750 2925);
PAINT GREEN (2750 2925);
FORCEPROP 1 LAST PATH I189
J 0
(2800 2900);
DISPLAY 0.872340 (2800 2900);
PAINT AQUA (2800 2900);
DISPLAY INVISIBLE (2800 2900);
FORCEPROP 2 LAST CDS_LIB logical_power
J 0
(2750 2875);
DISPLAY INVISIBLE (2750 2875);
FORCEADD OFFPAGE..2
(1125 4200);
FORCEPROP 2 LAST $XR0 12 
J 0
(1314 4200);
DISPLAY 0.638298 (1314 4200);
PAINT MONO (1314 4200);
FORCEPROP 2 LAST $XR1 10 
J 0
(1404 4200);
DISPLAY 0.638298 (1404 4200);
PAINT MONO (1404 4200);
FORCEPROP 2 LAST PATH I202
J 0
(1425 4250);
DISPLAY 0.680851 (1425 4250);
DISPLAY INVISIBLE (1425 4250);
FORCEPROP 1 LAST COMMENT_BODY TRUE
J 0
(1080 4105);
DISPLAY 0.872340 (1080 4105);
PAINT PEACH (1080 4105);
DISPLAY INVISIBLE (1080 4105);
FORCEPROP 1 LAST OFFPAGE TRUE
J 0
(1450 4075);
DISPLAY 0.872340 (1450 4075);
PAINT GREEN (1450 4075);
DISPLAY INVISIBLE (1450 4075);
FORCEPROP 2 LAST CDS_LIB standard
J 0
(1125 4200);
DISPLAY INVISIBLE (1125 4200);
FORCEADD UNIVERSAL_POWER..1
(-1075 4350);
FORCEPROP 3 LASTPIN (-1075 4300) SIG_NAME P3V3_AUX\g
J 0
(-1065 4310);
DISPLAY 0.659574 (-1065 4310);
PAINT MONO (-1065 4310);
DISPLAY INVISIBLE (-1065 4310);
FORCEPROP 1 LAST HDL_POWER P3V3_AUX
J 1
(-1075 4400);
DISPLAY 0.702128 (-1075 4400);
PAINT GREEN (-1075 4400);
FORCEPROP 1 LAST PATH I204
J 0
(-1025 4375);
DISPLAY 0.872340 (-1025 4375);
PAINT AQUA (-1025 4375);
DISPLAY INVISIBLE (-1025 4375);
FORCEPROP 2 LAST CDS_LIB logical_power
J 0
(-1075 4350);
DISPLAY INVISIBLE (-1075 4350);
FORCEADD OFFPAGE..2
(1125 4000);
FORCEPROP 2 LAST $XR1 10 
J 0
(1404 4000);
DISPLAY 0.638298 (1404 4000);
PAINT MONO (1404 4000);
FORCEPROP 2 LAST $XR0 12 
J 0
(1314 4000);
DISPLAY 0.638298 (1314 4000);
PAINT MONO (1314 4000);
FORCEPROP 2 LAST PATH I205
J 0
(1425 4050);
DISPLAY 0.680851 (1425 4050);
DISPLAY INVISIBLE (1425 4050);
FORCEPROP 1 LAST COMMENT_BODY TRUE
J 0
(1080 3905);
DISPLAY 0.872340 (1080 3905);
PAINT PEACH (1080 3905);
DISPLAY INVISIBLE (1080 3905);
FORCEPROP 1 LAST OFFPAGE TRUE
J 0
(1450 3875);
DISPLAY 0.872340 (1450 3875);
PAINT GREEN (1450 3875);
DISPLAY INVISIBLE (1450 3875);
FORCEPROP 2 LAST CDS_LIB standard
J 0
(1125 4000);
DISPLAY INVISIBLE (1125 4000);
FORCEADD OFFPAGE..2
(1125 3900);
FORCEPROP 2 LAST $XR1 12 
J 0
(1404 3900);
DISPLAY 0.638298 (1404 3900);
PAINT MONO (1404 3900);
FORCEPROP 2 LAST $XR0 10 
J 0
(1314 3900);
DISPLAY 0.638298 (1314 3900);
PAINT MONO (1314 3900);
FORCEPROP 2 LAST PATH I206
J 0
(1425 3950);
DISPLAY 0.680851 (1425 3950);
DISPLAY INVISIBLE (1425 3950);
FORCEPROP 1 LAST COMMENT_BODY TRUE
J 0
(1080 3805);
DISPLAY 0.872340 (1080 3805);
PAINT PEACH (1080 3805);
DISPLAY INVISIBLE (1080 3805);
FORCEPROP 1 LAST OFFPAGE TRUE
J 0
(1450 3775);
DISPLAY 0.872340 (1450 3775);
PAINT GREEN (1450 3775);
DISPLAY INVISIBLE (1450 3775);
FORCEPROP 2 LAST CDS_LIB standard
J 0
(1125 3900);
DISPLAY INVISIBLE (1125 3900);
FORCEADD OFFPAGE..2
(1125 4100);
FORCEPROP 2 LAST $XR1 12 
J 0
(1404 4100);
DISPLAY 0.638298 (1404 4100);
PAINT MONO (1404 4100);
FORCEPROP 2 LAST $XR0 10 
J 0
(1314 4100);
DISPLAY 0.638298 (1314 4100);
PAINT MONO (1314 4100);
FORCEPROP 2 LAST PATH I207
J 0
(1425 4150);
DISPLAY 0.680851 (1425 4150);
DISPLAY INVISIBLE (1425 4150);
FORCEPROP 1 LAST COMMENT_BODY TRUE
J 0
(1080 4005);
DISPLAY 0.872340 (1080 4005);
PAINT PEACH (1080 4005);
DISPLAY INVISIBLE (1080 4005);
FORCEPROP 1 LAST OFFPAGE TRUE
J 0
(1450 3975);
DISPLAY 0.872340 (1450 3975);
PAINT GREEN (1450 3975);
DISPLAY INVISIBLE (1450 3975);
FORCEPROP 2 LAST CDS_LIB standard
J 0
(1125 4100);
DISPLAY INVISIBLE (1125 4100);
FORCEADD OFFPAGE..5
R 2
(800 2725);
FORCEPROP 2 LAST $XR2 30 
J 0
(1169 2725);
DISPLAY 0.638298 (1169 2725);
PAINT MONO (1169 2725);
FORCEPROP 2 LAST $XR1 27 
J 0
(1079 2725);
DISPLAY 0.638298 (1079 2725);
PAINT MONO (1079 2725);
FORCEPROP 2 LAST $XR0 13 
J 0
(989 2725);
DISPLAY 0.638298 (989 2725);
PAINT MONO (989 2725);
FORCEPROP 2 LAST PATH I211
J 0
(1100 2775);
DISPLAY 0.680851 (1100 2775);
DISPLAY INVISIBLE (1100 2775);
FORCEPROP 1 LAST COMMENT_BODY TRUE
J 2
(700 2650);
DISPLAY 0.872340 (700 2650);
PAINT PEACH (700 2650);
DISPLAY INVISIBLE (700 2650);
FORCEPROP 1 LAST OFFPAGE TRUE
J 2
(475 2600);
DISPLAY 0.872340 (475 2600);
PAINT GREEN (475 2600);
DISPLAY INVISIBLE (475 2600);
FORCEPROP 2 LAST CDS_LIB standard
J 0
(800 2725);
DISPLAY INVISIBLE (800 2725);
FORCEADD Q_RES..1
(-675 2725);
FORCEPROP 1 LAST VALUE 4.7K
J 2
(-800 2725);
DISPLAY 0.510638 (-800 2725);
PAINT SKYBLUE (-800 2725);
FORCEPROP 1 LAST MATERIAL EMPTY
J 0
(-550 2725);
DISPLAY 0.510638 (-550 2725);
PAINT RED (-550 2725);
FORCEPROP 1 LAST PART_NUMBER CS24702FB06
J 0
(-725 2825);
DISPLAY 0.510638 (-725 2825);
PAINT WHITE (-725 2825);
DISPLAY INVISIBLE (-725 2825);
FORCEPROP 1 LAST PACK_TYPE 0402LF
J 0
(-425 2575);
DISPLAY 0.510638 (-425 2575);
PAINT SKYBLUE (-425 2575);
DISPLAY INVISIBLE (-425 2575);
FORCEPROP 1 LAST WATTAGE 1/16W
J 2
(-700 2575);
DISPLAY 0.510638 (-700 2575);
PAINT SKYBLUE (-700 2575);
DISPLAY INVISIBLE (-700 2575);
FORCEPROP 1 LAST PATH I213
J 0
(-725 2875);
DISPLAY 0.978723 (-725 2875);
PAINT WHITE (-725 2875);
DISPLAY INVISIBLE (-725 2875);
FORCEPROP 1 LAST TOLERANCE 1%
J 0
(-675 2625);
DISPLAY 0.510638 (-675 2625);
PAINT SKYBLUE (-675 2625);
DISPLAY INVISIBLE (-675 2625);
FORCEPROP 2 LAST CDS_LIB pure_quanta
J 0
(-675 2725);
DISPLAY INVISIBLE (-675 2725);
FORCEPROP 1 LAST LOCATION R754
J 0
(-1025 2725);
DISPLAY 0.702128 (-1025 2725);
PAINT YELLOW (-1025 2725);
FORCEPROP 0 LAST $SEC 1
J 0
(-1025 2775);
DISPLAY INVISIBLE (-1025 2775);
FORCEPROP 0 LAST CDS_SEC 1
J 0
(-1025 2775);
DISPLAY INVISIBLE (-1025 2775);
FORCEPROP 1 LASTPIN (-775 2725) $PN 1
J 0
(-763 2737);
DISPLAY 0.808511 (-763 2737);
PAINT WHITE (-763 2737);
DISPLAY INVISIBLE (-763 2737);
FORCEPROP 1 LASTPIN (-575 2725) $PN 2
J 0
(-613 2737);
DISPLAY 0.808511 (-613 2737);
PAINT WHITE (-613 2737);
DISPLAY INVISIBLE (-613 2737);
FORCEADD UNIVERSAL_POWER..1
(-1075 2975);
FORCEPROP 3 LASTPIN (-1075 2925) SIG_NAME P3V3_RGM\g
J 0
(-1065 2935);
DISPLAY 0.659574 (-1065 2935);
PAINT MONO (-1065 2935);
DISPLAY INVISIBLE (-1065 2935);
FORCEPROP 1 LAST HDL_POWER P3V3_RGM
J 1
(-1075 3025);
DISPLAY 0.702128 (-1075 3025);
PAINT GREEN (-1075 3025);
FORCEPROP 1 LAST PATH I214
J 0
(-1025 3000);
DISPLAY 0.872340 (-1025 3000);
PAINT AQUA (-1025 3000);
DISPLAY INVISIBLE (-1025 3000);
FORCEPROP 2 LAST CDS_LIB logical_power
J 0
(-1075 2975);
DISPLAY INVISIBLE (-1075 2975);
FORCEADD Q_RES..1
(-675 2525);
FORCEPROP 1 LAST VALUE 4.7K
J 2
(-800 2525);
DISPLAY 0.510638 (-800 2525);
PAINT SKYBLUE (-800 2525);
FORCEPROP 1 LAST MATERIAL EMPTY
J 0
(-550 2525);
DISPLAY 0.510638 (-550 2525);
PAINT RED (-550 2525);
FORCEPROP 1 LAST PART_NUMBER CS24702FB06
J 0
(-725 2625);
DISPLAY 0.510638 (-725 2625);
PAINT WHITE (-725 2625);
DISPLAY INVISIBLE (-725 2625);
FORCEPROP 1 LAST PACK_TYPE 0402LF
J 0
(-425 2375);
DISPLAY 0.510638 (-425 2375);
PAINT SKYBLUE (-425 2375);
DISPLAY INVISIBLE (-425 2375);
FORCEPROP 1 LAST WATTAGE 1/16W
J 2
(-700 2375);
DISPLAY 0.510638 (-700 2375);
PAINT SKYBLUE (-700 2375);
DISPLAY INVISIBLE (-700 2375);
FORCEPROP 1 LAST PATH I217
J 0
(-725 2675);
DISPLAY 0.978723 (-725 2675);
PAINT WHITE (-725 2675);
DISPLAY INVISIBLE (-725 2675);
FORCEPROP 1 LAST TOLERANCE 1%
J 0
(-675 2425);
DISPLAY 0.510638 (-675 2425);
PAINT SKYBLUE (-675 2425);
DISPLAY INVISIBLE (-675 2425);
FORCEPROP 2 LAST CDS_LIB pure_quanta
J 0
(-675 2525);
DISPLAY INVISIBLE (-675 2525);
FORCEPROP 1 LAST LOCATION R770
J 0
(-1025 2525);
DISPLAY 0.702128 (-1025 2525);
PAINT YELLOW (-1025 2525);
FORCEPROP 0 LAST $SEC 1
J 0
(-1025 2575);
DISPLAY INVISIBLE (-1025 2575);
FORCEPROP 0 LAST CDS_SEC 1
J 0
(-1025 2575);
DISPLAY INVISIBLE (-1025 2575);
FORCEPROP 1 LASTPIN (-775 2525) $PN 1
J 0
(-763 2537);
DISPLAY 0.808511 (-763 2537);
PAINT WHITE (-763 2537);
DISPLAY INVISIBLE (-763 2537);
FORCEPROP 1 LASTPIN (-575 2525) $PN 2
J 0
(-613 2537);
DISPLAY 0.808511 (-613 2537);
PAINT WHITE (-613 2537);
DISPLAY INVISIBLE (-613 2537);
FORCEADD UNIVERSAL_GND..1
R 2
(-1075 2325);
FORCEPROP 3 LASTPIN (-1075 2375) SIG_NAME GND\g
J 0
(-1065 2385);
DISPLAY 0.659574 (-1065 2385);
PAINT MONO (-1065 2385);
DISPLAY INVISIBLE (-1065 2385);
FORCEPROP 1 LAST PATH I218
J 2
(-1150 2325);
DISPLAY 0.872340 (-1150 2325);
PAINT AQUA (-1150 2325);
DISPLAY INVISIBLE (-1150 2325);
FORCEPROP 1 LAST HDL_POWER GND
J 1
(-1100 2250);
DISPLAY 0.702128 (-1100 2250);
PAINT GREEN (-1100 2250);
DISPLAY INVISIBLE (-1100 2250);
FORCEPROP 2 LAST CDS_LIB logical_power
J 0
(-1075 2325);
DISPLAY INVISIBLE (-1075 2325);
FORCEADD Q_RES..2
(2375 -275);
FORCEPROP 1 LAST VALUE 4.7K
J 0
(2420 -200);
DISPLAY 0.787234 (2420 -200);
FORCEPROP 1 LAST TOLERANCE 1%
J 0
(2420 -250);
DISPLAY 0.787234 (2420 -250);
FORCEPROP 1 LAST PACK_TYPE 0402LF
J 0
(2415 -450);
DISPLAY 0.787234 (2415 -450);
FORCEPROP 1 LAST PART_NUMBER CS24702FB06
J 0
(2415 -400);
DISPLAY 0.787234 (2415 -400);
FORCEPROP 1 LAST MATERIAL CHIP
J 0
(2415 -350);
DISPLAY 0.787234 (2415 -350);
FORCEPROP 2 LAST CDS_LIB pure_quanta
J 0
(2375 -275);
DISPLAY INVISIBLE (2375 -275);
FORCEPROP 1 LAST PATH I222
J 0
(2425 -100);
DISPLAY 0.978723 (2425 -100);
PAINT WHITE (2425 -100);
DISPLAY INVISIBLE (2425 -100);
FORCEPROP 1 LAST WATTAGE 1/16W
J 0
(2415 -300);
DISPLAY 0.787234 (2415 -300);
DISPLAY INVISIBLE (2415 -300);
FORCEPROP 1 LAST LOCATION R42
J 0
(2420 -150);
DISPLAY 0.787234 (2420 -150);
FORCEPROP 1 LASTPIN (2375 -175) $PN 1
J 0
(2380 -213);
DISPLAY 0.787234 (2380 -213);
PAINT MONO (2380 -213);
FORCEPROP 1 LASTPIN (2375 -375) $PN 2
J 0
(2380 -365);
DISPLAY 0.787234 (2380 -365);
PAINT MONO (2380 -365);
FORCEPROP 0 LAST $SEC 1
J 0
(2425 -100);
DISPLAY 0.680851 (2425 -100);
PAINT MONO (2425 -100);
DISPLAY INVISIBLE (2425 -100);
FORCEPROP 0 LAST CDS_SEC 1
J 0
(2425 -100);
DISPLAY 0.680851 (2425 -100);
DISPLAY INVISIBLE (2425 -100);
FORCEADD UNIVERSAL_GND..1
R 2
(-3325 -1300);
FORCEPROP 3 LASTPIN (-3325 -1250) SIG_NAME GND\g
J 0
(-3315 -1240);
DISPLAY 0.659574 (-3315 -1240);
PAINT MONO (-3315 -1240);
DISPLAY INVISIBLE (-3315 -1240);
FORCEPROP 1 LAST PATH I223
J 2
(-3400 -1300);
DISPLAY 0.872340 (-3400 -1300);
PAINT AQUA (-3400 -1300);
DISPLAY INVISIBLE (-3400 -1300);
FORCEPROP 2 LAST CDS_LIB logical_power
J 0
(-3325 -1300);
DISPLAY INVISIBLE (-3325 -1300);
FORCEPROP 1 LAST HDL_POWER GND
J 1
(-3350 -1375);
DISPLAY 0.702128 (-3350 -1375);
PAINT GREEN (-3350 -1375);
DISPLAY INVISIBLE (-3350 -1375);
FORCEADD Q_RES..2
(-3325 -150);
FORCEPROP 1 LAST VALUE 4.7K
J 0
(-3275 -75);
DISPLAY 0.510638 (-3275 -75);
PAINT SKYBLUE (-3275 -75);
FORCEPROP 1 LAST TOLERANCE 1%
J 0
(-3275 -125);
DISPLAY 0.510638 (-3275 -125);
PAINT SKYBLUE (-3275 -125);
FORCEPROP 1 LAST PACK_TYPE 0402LF
J 0
(-3275 -175);
DISPLAY 0.510638 (-3275 -175);
PAINT SKYBLUE (-3275 -175);
FORCEPROP 1 LAST MATERIAL EMPTY
J 0
(-3275 -275);
DISPLAY 0.510638 (-3275 -275);
PAINT RED (-3275 -275);
FORCEPROP 1 LAST WATTAGE 1/16W
J 0
(-3275 -225);
DISPLAY 0.510638 (-3275 -225);
PAINT SKYBLUE (-3275 -225);
FORCEPROP 2 LAST CDS_LIB pure_quanta
J 0
(-3325 -150);
DISPLAY INVISIBLE (-3325 -150);
FORCEPROP 1 LAST PATH I228
J 0
(-3275 25);
DISPLAY 0.978723 (-3275 25);
PAINT WHITE (-3275 25);
DISPLAY INVISIBLE (-3275 25);
FORCEPROP 1 LAST PART_NUMBER CS24702FB06
J 0
(-3280 -275);
DISPLAY 0.510638 (-3280 -275);
PAINT WHITE (-3280 -275);
DISPLAY INVISIBLE (-3280 -275);
FORCEPROP 1 LAST LOCATION R140
J 0
(-3280 -25);
DISPLAY 0.702128 (-3280 -25);
PAINT YELLOW (-3280 -25);
FORCEPROP 1 LASTPIN (-3325 -50) $PN 1
J 0
(-3320 -88);
DISPLAY 0.808511 (-3320 -88);
PAINT WHITE (-3320 -88);
FORCEPROP 1 LASTPIN (-3325 -250) $PN 2
J 0
(-3320 -240);
DISPLAY 0.808511 (-3320 -240);
PAINT WHITE (-3320 -240);
FORCEPROP 0 LAST $SEC 1
J 0
(-3275 25);
DISPLAY 0.680851 (-3275 25);
PAINT MONO (-3275 25);
DISPLAY INVISIBLE (-3275 25);
FORCEPROP 0 LAST CDS_SEC 1
J 0
(-3275 25);
DISPLAY 0.680851 (-3275 25);
DISPLAY INVISIBLE (-3275 25);
FORCEADD OFFPAGE..2
(-75 -500);
FORCEPROP 2 LAST $XR0 13 
J 0
(114 -500);
DISPLAY 0.638298 (114 -500);
PAINT MONO (114 -500);
FORCEPROP 2 LAST $XR1 21 
J 0
(204 -500);
DISPLAY 0.638298 (204 -500);
PAINT MONO (204 -500);
FORCEPROP 2 LAST CDS_LIB standard
J 0
(-75 -500);
DISPLAY INVISIBLE (-75 -500);
FORCEPROP 1 LAST OFFPAGE TRUE
J 0
(250 -625);
DISPLAY 0.872340 (250 -625);
PAINT GREEN (250 -625);
DISPLAY INVISIBLE (250 -625);
FORCEPROP 1 LAST COMMENT_BODY TRUE
J 0
(-120 -595);
DISPLAY 0.872340 (-120 -595);
PAINT PEACH (-120 -595);
DISPLAY INVISIBLE (-120 -595);
FORCEPROP 2 LAST PATH I229
J 0
(225 -450);
DISPLAY 0.680851 (225 -450);
DISPLAY INVISIBLE (225 -450);
FORCEADD OFFPAGE..2
(-100 -650);
FORCEPROP 2 LAST $XR0 21 
J 0
(89 -650);
DISPLAY 0.638298 (89 -650);
PAINT MONO (89 -650);
FORCEPROP 2 LAST $XR1 13 
J 0
(179 -650);
DISPLAY 0.638298 (179 -650);
PAINT MONO (179 -650);
FORCEPROP 2 LAST CDS_LIB standard
J 0
(-100 -650);
DISPLAY INVISIBLE (-100 -650);
FORCEPROP 1 LAST OFFPAGE TRUE
J 0
(225 -775);
DISPLAY 0.872340 (225 -775);
PAINT GREEN (225 -775);
DISPLAY INVISIBLE (225 -775);
FORCEPROP 1 LAST COMMENT_BODY TRUE
J 0
(-145 -745);
DISPLAY 0.872340 (-145 -745);
PAINT PEACH (-145 -745);
DISPLAY INVISIBLE (-145 -745);
FORCEPROP 2 LAST PATH I230
J 0
(200 -600);
DISPLAY 0.680851 (200 -600);
DISPLAY INVISIBLE (200 -600);
FORCEADD VCCAUX15..1
(-3325 175);
FORCEPROP 3 LASTPIN (-3325 125) SIG_NAME P3V3_AUX\g
J 0
(-3315 135);
DISPLAY 0.659574 (-3315 135);
PAINT MONO (-3315 135);
DISPLAY INVISIBLE (-3315 135);
FORCEPROP 1 LAST HDL_POWER P3V3_AUX
J 1
(-3325 225);
DISPLAY 0.702128 (-3325 225);
PAINT GREEN (-3325 225);
FORCEPROP 1 LAST PATH I231
J 0
(-3275 200);
DISPLAY 0.872340 (-3275 200);
PAINT AQUA (-3275 200);
DISPLAY INVISIBLE (-3275 200);
FORCEPROP 2 LAST CDS_LIB logical_power
J 0
(-3325 175);
DISPLAY INVISIBLE (-3325 175);
FORCEADD VCCAUX15..1
(-2825 175);
FORCEPROP 3 LASTPIN (-2825 125) SIG_NAME P3V3_AUX\g
J 0
(-2815 135);
DISPLAY 0.659574 (-2815 135);
PAINT MONO (-2815 135);
DISPLAY INVISIBLE (-2815 135);
FORCEPROP 1 LAST HDL_POWER P3V3_AUX
J 1
(-2825 225);
DISPLAY 0.702128 (-2825 225);
PAINT GREEN (-2825 225);
FORCEPROP 1 LAST PATH I232
J 0
(-2775 200);
DISPLAY 0.872340 (-2775 200);
PAINT AQUA (-2775 200);
DISPLAY INVISIBLE (-2775 200);
FORCEPROP 2 LAST CDS_LIB logical_power
J 0
(-2825 175);
DISPLAY INVISIBLE (-2825 175);
FORCEADD Q_RES..2
(-2825 -150);
FORCEPROP 1 LAST WATTAGE 1/16W
J 0
(-2775 -225);
DISPLAY 0.510638 (-2775 -225);
PAINT SKYBLUE (-2775 -225);
FORCEPROP 1 LAST VALUE 4.7K
J 0
(-2775 -75);
DISPLAY 0.510638 (-2775 -75);
PAINT SKYBLUE (-2775 -75);
FORCEPROP 1 LAST TOLERANCE 1%
J 0
(-2775 -125);
DISPLAY 0.510638 (-2775 -125);
PAINT SKYBLUE (-2775 -125);
FORCEPROP 1 LAST PACK_TYPE 0402LF
J 0
(-2775 -175);
DISPLAY 0.510638 (-2775 -175);
PAINT SKYBLUE (-2775 -175);
FORCEPROP 1 LAST MATERIAL EMPTY
J 0
(-2775 -275);
DISPLAY 0.510638 (-2775 -275);
PAINT RED (-2775 -275);
FORCEPROP 1 LAST PATH I233
J 0
(-2775 25);
DISPLAY 0.978723 (-2775 25);
PAINT WHITE (-2775 25);
DISPLAY INVISIBLE (-2775 25);
FORCEPROP 1 LAST PART_NUMBER CS24702FB06
J 0
(-2780 -275);
DISPLAY 0.510638 (-2780 -275);
PAINT WHITE (-2780 -275);
DISPLAY INVISIBLE (-2780 -275);
FORCEPROP 2 LAST CDS_LIB pure_quanta
J 0
(-2825 -150);
DISPLAY INVISIBLE (-2825 -150);
FORCEPROP 1 LAST LOCATION R753
J 0
(-2780 -25);
DISPLAY 0.702128 (-2780 -25);
PAINT YELLOW (-2780 -25);
FORCEPROP 1 LASTPIN (-2825 -50) $PN 1
J 0
(-2820 -88);
DISPLAY 0.808511 (-2820 -88);
PAINT WHITE (-2820 -88);
FORCEPROP 1 LASTPIN (-2825 -250) $PN 2
J 0
(-2820 -240);
DISPLAY 0.808511 (-2820 -240);
PAINT WHITE (-2820 -240);
FORCEPROP 0 LAST $SEC 1
J 0
(-2775 25);
DISPLAY 0.680851 (-2775 25);
PAINT MONO (-2775 25);
DISPLAY INVISIBLE (-2775 25);
FORCEPROP 0 LAST CDS_SEC 1
J 0
(-2775 25);
DISPLAY 0.680851 (-2775 25);
DISPLAY INVISIBLE (-2775 25);
FORCEADD Q_RES..1
(-3625 2275);
FORCEPROP 1 LAST VALUE 10K
J 2
(-3750 2275);
DISPLAY 0.510638 (-3750 2275);
PAINT SKYBLUE (-3750 2275);
FORCEPROP 1 LAST MATERIAL CHIP
J 0
(-3500 2275);
DISPLAY 0.510638 (-3500 2275);
PAINT SKYBLUE (-3500 2275);
FORCEPROP 1 LAST PART_NUMBER CS31002FB08
J 0
(-3675 2375);
DISPLAY 0.510638 (-3675 2375);
PAINT WHITE (-3675 2375);
DISPLAY INVISIBLE (-3675 2375);
FORCEPROP 1 LAST TOLERANCE 1%
J 0
(-3625 2175);
DISPLAY 0.510638 (-3625 2175);
PAINT SKYBLUE (-3625 2175);
DISPLAY INVISIBLE (-3625 2175);
FORCEPROP 2 LAST CDS_LIB pure_quanta
J 0
(-3625 2275);
DISPLAY INVISIBLE (-3625 2275);
FORCEPROP 1 LAST PATH I234
J 0
(-3675 2425);
DISPLAY 0.978723 (-3675 2425);
PAINT WHITE (-3675 2425);
DISPLAY INVISIBLE (-3675 2425);
FORCEPROP 1 LAST PACK_TYPE 0402LF
J 0
(-3375 2125);
DISPLAY 0.510638 (-3375 2125);
PAINT SKYBLUE (-3375 2125);
DISPLAY INVISIBLE (-3375 2125);
FORCEPROP 1 LAST WATTAGE 1/16W
J 2
(-3650 2125);
DISPLAY 0.510638 (-3650 2125);
PAINT SKYBLUE (-3650 2125);
DISPLAY INVISIBLE (-3650 2125);
FORCEPROP 1 LAST LOCATION R521
J 0
(-3975 2275);
DISPLAY 0.702128 (-3975 2275);
PAINT YELLOW (-3975 2275);
FORCEPROP 1 LASTPIN (-3725 2275) $PN 1
J 0
(-3713 2287);
DISPLAY 0.787234 (-3713 2287);
PAINT MONO (-3713 2287);
FORCEPROP 1 LASTPIN (-3525 2275) $PN 2
J 0
(-3563 2287);
DISPLAY 0.787234 (-3563 2287);
PAINT MONO (-3563 2287);
FORCEPROP 0 LAST $SEC 1
J 0
(-3975 2325);
DISPLAY 0.680851 (-3975 2325);
PAINT MONO (-3975 2325);
DISPLAY INVISIBLE (-3975 2325);
FORCEPROP 0 LAST CDS_SEC 1
J 0
(-3975 2325);
DISPLAY 0.680851 (-3975 2325);
DISPLAY INVISIBLE (-3975 2325);
FORCEADD Q_RES..1
(-3625 2175);
FORCEPROP 1 LAST MATERIAL CHIP
J 0
(-3500 2175);
DISPLAY 0.510638 (-3500 2175);
PAINT SKYBLUE (-3500 2175);
FORCEPROP 1 LAST VALUE 10K
J 2
(-3750 2175);
DISPLAY 0.510638 (-3750 2175);
PAINT SKYBLUE (-3750 2175);
FORCEPROP 1 LAST PART_NUMBER CS31002FB08
J 0
(-3675 2275);
DISPLAY 0.510638 (-3675 2275);
PAINT WHITE (-3675 2275);
DISPLAY INVISIBLE (-3675 2275);
FORCEPROP 1 LAST TOLERANCE 1%
J 0
(-3625 2075);
DISPLAY 0.510638 (-3625 2075);
PAINT SKYBLUE (-3625 2075);
DISPLAY INVISIBLE (-3625 2075);
FORCEPROP 2 LAST CDS_LIB pure_quanta
J 0
(-3625 2175);
DISPLAY INVISIBLE (-3625 2175);
FORCEPROP 1 LAST PATH I235
J 0
(-3675 2325);
DISPLAY 0.978723 (-3675 2325);
PAINT WHITE (-3675 2325);
DISPLAY INVISIBLE (-3675 2325);
FORCEPROP 1 LAST WATTAGE 1/16W
J 2
(-3650 2025);
DISPLAY 0.510638 (-3650 2025);
PAINT SKYBLUE (-3650 2025);
DISPLAY INVISIBLE (-3650 2025);
FORCEPROP 1 LAST PACK_TYPE 0402LF
J 0
(-3375 2025);
DISPLAY 0.510638 (-3375 2025);
PAINT SKYBLUE (-3375 2025);
DISPLAY INVISIBLE (-3375 2025);
FORCEPROP 1 LAST LOCATION R145
J 0
(-3975 2175);
DISPLAY 0.702128 (-3975 2175);
PAINT YELLOW (-3975 2175);
FORCEPROP 1 LASTPIN (-3725 2175) $PN 1
J 0
(-3713 2187);
DISPLAY 0.787234 (-3713 2187);
PAINT MONO (-3713 2187);
FORCEPROP 1 LASTPIN (-3525 2175) $PN 2
J 0
(-3563 2187);
DISPLAY 0.787234 (-3563 2187);
PAINT MONO (-3563 2187);
FORCEPROP 0 LAST $SEC 1
J 0
(-3975 2225);
DISPLAY 0.680851 (-3975 2225);
PAINT MONO (-3975 2225);
DISPLAY INVISIBLE (-3975 2225);
FORCEPROP 0 LAST CDS_SEC 1
J 0
(-3975 2225);
DISPLAY 0.680851 (-3975 2225);
DISPLAY INVISIBLE (-3975 2225);
FORCEADD Q_RES..1
(-3625 2075);
FORCEPROP 1 LAST VALUE 10K
J 2
(-3750 2075);
DISPLAY 0.510638 (-3750 2075);
PAINT SKYBLUE (-3750 2075);
FORCEPROP 1 LAST MATERIAL CHIP
J 0
(-3500 2075);
DISPLAY 0.510638 (-3500 2075);
PAINT SKYBLUE (-3500 2075);
FORCEPROP 1 LAST PART_NUMBER CS31002FB08
J 0
(-3675 2175);
DISPLAY 0.510638 (-3675 2175);
PAINT WHITE (-3675 2175);
DISPLAY INVISIBLE (-3675 2175);
FORCEPROP 1 LAST TOLERANCE 1%
J 0
(-3625 1975);
DISPLAY 0.510638 (-3625 1975);
PAINT SKYBLUE (-3625 1975);
DISPLAY INVISIBLE (-3625 1975);
FORCEPROP 2 LAST CDS_LIB pure_quanta
J 0
(-3625 2075);
DISPLAY INVISIBLE (-3625 2075);
FORCEPROP 1 LAST PATH I236
J 0
(-3675 2225);
DISPLAY 0.978723 (-3675 2225);
PAINT WHITE (-3675 2225);
DISPLAY INVISIBLE (-3675 2225);
FORCEPROP 1 LAST WATTAGE 1/16W
J 2
(-3650 1925);
DISPLAY 0.510638 (-3650 1925);
PAINT SKYBLUE (-3650 1925);
DISPLAY INVISIBLE (-3650 1925);
FORCEPROP 1 LAST PACK_TYPE 0402LF
J 0
(-3375 1925);
DISPLAY 0.510638 (-3375 1925);
PAINT SKYBLUE (-3375 1925);
DISPLAY INVISIBLE (-3375 1925);
FORCEPROP 1 LAST LOCATION R149
J 0
(-3975 2075);
DISPLAY 0.702128 (-3975 2075);
PAINT YELLOW (-3975 2075);
FORCEPROP 1 LASTPIN (-3725 2075) $PN 1
J 0
(-3713 2087);
DISPLAY 0.787234 (-3713 2087);
PAINT MONO (-3713 2087);
FORCEPROP 1 LASTPIN (-3525 2075) $PN 2
J 0
(-3563 2087);
DISPLAY 0.787234 (-3563 2087);
PAINT MONO (-3563 2087);
FORCEPROP 0 LAST $SEC 1
J 0
(-3975 2125);
DISPLAY 0.680851 (-3975 2125);
PAINT MONO (-3975 2125);
DISPLAY INVISIBLE (-3975 2125);
FORCEPROP 0 LAST CDS_SEC 1
J 0
(-3975 2125);
DISPLAY 0.680851 (-3975 2125);
DISPLAY INVISIBLE (-3975 2125);
FORCEADD Q_RES..1
(-3625 1975);
FORCEPROP 1 LAST VALUE 2.2K
J 2
(-3750 1975);
DISPLAY 0.510638 (-3750 1975);
PAINT SKYBLUE (-3750 1975);
FORCEPROP 1 LAST MATERIAL CHIP
J 0
(-3500 1975);
DISPLAY 0.510638 (-3500 1975);
PAINT SKYBLUE (-3500 1975);
FORCEPROP 1 LAST PACK_TYPE 0402LF
J 0
(-3375 1825);
DISPLAY 0.510638 (-3375 1825);
PAINT SKYBLUE (-3375 1825);
DISPLAY INVISIBLE (-3375 1825);
FORCEPROP 1 LAST WATTAGE 1/16W
J 2
(-3650 1825);
DISPLAY 0.510638 (-3650 1825);
PAINT SKYBLUE (-3650 1825);
DISPLAY INVISIBLE (-3650 1825);
FORCEPROP 1 LAST PART_NUMBER CS22202JB07
J 0
(-3675 2075);
DISPLAY 0.510638 (-3675 2075);
PAINT WHITE (-3675 2075);
DISPLAY INVISIBLE (-3675 2075);
FORCEPROP 1 LAST TOLERANCE 5%
J 0
(-3625 1875);
DISPLAY 0.510638 (-3625 1875);
PAINT SKYBLUE (-3625 1875);
DISPLAY INVISIBLE (-3625 1875);
FORCEPROP 1 LAST PATH I237
J 0
(-3675 2125);
DISPLAY 0.978723 (-3675 2125);
PAINT WHITE (-3675 2125);
DISPLAY INVISIBLE (-3675 2125);
FORCEPROP 2 LAST CDS_LIB pure_quanta
J 0
(-3625 1975);
DISPLAY INVISIBLE (-3625 1975);
FORCEPROP 1 LAST LOCATION R610
J 0
(-3975 1975);
DISPLAY 0.702128 (-3975 1975);
PAINT YELLOW (-3975 1975);
FORCEPROP 1 LASTPIN (-3725 1975) $PN 1
J 0
(-3713 1987);
DISPLAY 0.787234 (-3713 1987);
PAINT MONO (-3713 1987);
FORCEPROP 1 LASTPIN (-3525 1975) $PN 2
J 0
(-3563 1987);
DISPLAY 0.787234 (-3563 1987);
PAINT MONO (-3563 1987);
FORCEPROP 0 LAST $SEC 1
J 0
(-3975 2025);
DISPLAY 0.680851 (-3975 2025);
PAINT MONO (-3975 2025);
DISPLAY INVISIBLE (-3975 2025);
FORCEPROP 0 LAST CDS_SEC 1
J 0
(-3975 2025);
DISPLAY 0.680851 (-3975 2025);
DISPLAY INVISIBLE (-3975 2025);
FORCEADD Q_RES..1
(-3625 1875);
FORCEPROP 1 LAST VALUE 2.2K
J 2
(-3750 1875);
DISPLAY 0.510638 (-3750 1875);
PAINT SKYBLUE (-3750 1875);
FORCEPROP 1 LAST MATERIAL CHIP
J 0
(-3500 1875);
DISPLAY 0.510638 (-3500 1875);
PAINT SKYBLUE (-3500 1875);
FORCEPROP 1 LAST PACK_TYPE 0402LF
J 0
(-3375 1725);
DISPLAY 0.510638 (-3375 1725);
PAINT SKYBLUE (-3375 1725);
DISPLAY INVISIBLE (-3375 1725);
FORCEPROP 1 LAST WATTAGE 1/16W
J 2
(-3650 1725);
DISPLAY 0.510638 (-3650 1725);
PAINT SKYBLUE (-3650 1725);
DISPLAY INVISIBLE (-3650 1725);
FORCEPROP 1 LAST PART_NUMBER CS22202JB07
J 0
(-3675 1975);
DISPLAY 0.510638 (-3675 1975);
PAINT WHITE (-3675 1975);
DISPLAY INVISIBLE (-3675 1975);
FORCEPROP 1 LAST TOLERANCE 5%
J 0
(-3625 1775);
DISPLAY 0.510638 (-3625 1775);
PAINT SKYBLUE (-3625 1775);
DISPLAY INVISIBLE (-3625 1775);
FORCEPROP 1 LAST PATH I238
J 0
(-3675 2025);
DISPLAY 0.978723 (-3675 2025);
PAINT WHITE (-3675 2025);
DISPLAY INVISIBLE (-3675 2025);
FORCEPROP 2 LAST CDS_LIB pure_quanta
J 0
(-3625 1875);
DISPLAY INVISIBLE (-3625 1875);
FORCEPROP 1 LAST LOCATION R692
J 0
(-3975 1875);
DISPLAY 0.702128 (-3975 1875);
PAINT YELLOW (-3975 1875);
FORCEPROP 1 LASTPIN (-3725 1875) $PN 1
J 0
(-3713 1887);
DISPLAY 0.787234 (-3713 1887);
PAINT MONO (-3713 1887);
FORCEPROP 1 LASTPIN (-3525 1875) $PN 2
J 0
(-3563 1887);
DISPLAY 0.787234 (-3563 1887);
PAINT MONO (-3563 1887);
FORCEPROP 0 LAST $SEC 1
J 0
(-3975 1925);
DISPLAY 0.680851 (-3975 1925);
PAINT MONO (-3975 1925);
DISPLAY INVISIBLE (-3975 1925);
FORCEPROP 0 LAST CDS_SEC 1
J 0
(-3975 1925);
DISPLAY 0.680851 (-3975 1925);
DISPLAY INVISIBLE (-3975 1925);
FORCEADD Q_RES..1
(-625 4200);
FORCEPROP 1 LAST MATERIAL CHIP
J 0
(-500 4200);
DISPLAY 0.510638 (-500 4200);
PAINT SKYBLUE (-500 4200);
FORCEPROP 1 LAST VALUE 2.2K
J 2
(-750 4200);
DISPLAY 0.510638 (-750 4200);
PAINT SKYBLUE (-750 4200);
FORCEPROP 1 LAST PACK_TYPE 0402LF
J 0
(-375 4050);
DISPLAY 0.510638 (-375 4050);
PAINT SKYBLUE (-375 4050);
DISPLAY INVISIBLE (-375 4050);
FORCEPROP 1 LAST WATTAGE 1/16W
J 2
(-650 4050);
DISPLAY 0.510638 (-650 4050);
PAINT SKYBLUE (-650 4050);
DISPLAY INVISIBLE (-650 4050);
FORCEPROP 1 LAST PART_NUMBER CS22202JB07
J 0
(-675 4300);
DISPLAY 0.510638 (-675 4300);
PAINT WHITE (-675 4300);
DISPLAY INVISIBLE (-675 4300);
FORCEPROP 1 LAST TOLERANCE 5%
J 0
(-625 4100);
DISPLAY 0.510638 (-625 4100);
PAINT SKYBLUE (-625 4100);
DISPLAY INVISIBLE (-625 4100);
FORCEPROP 1 LAST PATH I239
J 0
(-675 4350);
DISPLAY 0.978723 (-675 4350);
PAINT WHITE (-675 4350);
DISPLAY INVISIBLE (-675 4350);
FORCEPROP 2 LAST CDS_LIB pure_quanta
J 0
(-625 4200);
DISPLAY INVISIBLE (-625 4200);
FORCEPROP 1 LAST LOCATION R422
J 0
(-975 4200);
DISPLAY 0.702128 (-975 4200);
PAINT YELLOW (-975 4200);
FORCEPROP 1 LASTPIN (-725 4200) $PN 1
J 0
(-713 4212);
DISPLAY 0.787234 (-713 4212);
PAINT MONO (-713 4212);
FORCEPROP 1 LASTPIN (-525 4200) $PN 2
J 0
(-563 4212);
DISPLAY 0.787234 (-563 4212);
PAINT MONO (-563 4212);
FORCEPROP 0 LAST $SEC 1
J 0
(-975 4250);
DISPLAY 0.680851 (-975 4250);
PAINT MONO (-975 4250);
DISPLAY INVISIBLE (-975 4250);
FORCEPROP 0 LAST CDS_SEC 1
J 0
(-975 4250);
DISPLAY 0.680851 (-975 4250);
DISPLAY INVISIBLE (-975 4250);
FORCEADD Q_RES..1
(-625 4100);
FORCEPROP 1 LAST MATERIAL CHIP
J 0
(-500 4100);
DISPLAY 0.510638 (-500 4100);
PAINT SKYBLUE (-500 4100);
FORCEPROP 1 LAST VALUE 2.2K
J 2
(-750 4100);
DISPLAY 0.510638 (-750 4100);
PAINT SKYBLUE (-750 4100);
FORCEPROP 1 LAST PACK_TYPE 0402LF
J 0
(-375 3950);
DISPLAY 0.510638 (-375 3950);
PAINT SKYBLUE (-375 3950);
DISPLAY INVISIBLE (-375 3950);
FORCEPROP 1 LAST WATTAGE 1/16W
J 2
(-650 3950);
DISPLAY 0.510638 (-650 3950);
PAINT SKYBLUE (-650 3950);
DISPLAY INVISIBLE (-650 3950);
FORCEPROP 1 LAST PART_NUMBER CS22202JB07
J 0
(-675 4200);
DISPLAY 0.510638 (-675 4200);
PAINT WHITE (-675 4200);
DISPLAY INVISIBLE (-675 4200);
FORCEPROP 1 LAST TOLERANCE 5%
J 0
(-625 4000);
DISPLAY 0.510638 (-625 4000);
PAINT SKYBLUE (-625 4000);
DISPLAY INVISIBLE (-625 4000);
FORCEPROP 1 LAST PATH I240
J 0
(-675 4250);
DISPLAY 0.978723 (-675 4250);
PAINT WHITE (-675 4250);
DISPLAY INVISIBLE (-675 4250);
FORCEPROP 2 LAST CDS_LIB pure_quanta
J 0
(-625 4100);
DISPLAY INVISIBLE (-625 4100);
FORCEPROP 1 LAST LOCATION R428
J 0
(-975 4100);
DISPLAY 0.702128 (-975 4100);
PAINT YELLOW (-975 4100);
FORCEPROP 1 LASTPIN (-725 4100) $PN 1
J 0
(-713 4112);
DISPLAY 0.787234 (-713 4112);
PAINT MONO (-713 4112);
FORCEPROP 1 LASTPIN (-525 4100) $PN 2
J 0
(-563 4112);
DISPLAY 0.787234 (-563 4112);
PAINT MONO (-563 4112);
FORCEPROP 0 LAST $SEC 1
J 0
(-975 4150);
DISPLAY 0.680851 (-975 4150);
PAINT MONO (-975 4150);
DISPLAY INVISIBLE (-975 4150);
FORCEPROP 0 LAST CDS_SEC 1
J 0
(-975 4150);
DISPLAY 0.680851 (-975 4150);
DISPLAY INVISIBLE (-975 4150);
FORCEADD Q_RES..1
(-625 4000);
FORCEPROP 1 LAST MATERIAL CHIP
J 0
(-500 4000);
DISPLAY 0.510638 (-500 4000);
PAINT SKYBLUE (-500 4000);
FORCEPROP 1 LAST VALUE 2.2K
J 2
(-750 4000);
DISPLAY 0.510638 (-750 4000);
PAINT SKYBLUE (-750 4000);
FORCEPROP 1 LAST PACK_TYPE 0402LF
J 0
(-375 3850);
DISPLAY 0.510638 (-375 3850);
PAINT SKYBLUE (-375 3850);
DISPLAY INVISIBLE (-375 3850);
FORCEPROP 1 LAST WATTAGE 1/16W
J 2
(-650 3850);
DISPLAY 0.510638 (-650 3850);
PAINT SKYBLUE (-650 3850);
DISPLAY INVISIBLE (-650 3850);
FORCEPROP 1 LAST PART_NUMBER CS22202JB07
J 0
(-675 4100);
DISPLAY 0.510638 (-675 4100);
PAINT WHITE (-675 4100);
DISPLAY INVISIBLE (-675 4100);
FORCEPROP 1 LAST TOLERANCE 5%
J 0
(-625 3900);
DISPLAY 0.510638 (-625 3900);
PAINT SKYBLUE (-625 3900);
DISPLAY INVISIBLE (-625 3900);
FORCEPROP 1 LAST PATH I241
J 0
(-675 4150);
DISPLAY 0.978723 (-675 4150);
PAINT WHITE (-675 4150);
DISPLAY INVISIBLE (-675 4150);
FORCEPROP 2 LAST CDS_LIB pure_quanta
J 0
(-625 4000);
DISPLAY INVISIBLE (-625 4000);
FORCEPROP 1 LAST LOCATION R429
J 0
(-975 4000);
DISPLAY 0.702128 (-975 4000);
PAINT YELLOW (-975 4000);
FORCEPROP 1 LASTPIN (-725 4000) $PN 1
J 0
(-713 4012);
DISPLAY 0.787234 (-713 4012);
PAINT MONO (-713 4012);
FORCEPROP 1 LASTPIN (-525 4000) $PN 2
J 0
(-563 4012);
DISPLAY 0.787234 (-563 4012);
PAINT MONO (-563 4012);
FORCEPROP 0 LAST $SEC 1
J 0
(-975 4050);
DISPLAY 0.680851 (-975 4050);
PAINT MONO (-975 4050);
DISPLAY INVISIBLE (-975 4050);
FORCEPROP 0 LAST CDS_SEC 1
J 0
(-975 4050);
DISPLAY 0.680851 (-975 4050);
DISPLAY INVISIBLE (-975 4050);
FORCEADD Q_RES..1
(-625 3900);
FORCEPROP 1 LAST MATERIAL CHIP
J 0
(-500 3900);
DISPLAY 0.510638 (-500 3900);
PAINT SKYBLUE (-500 3900);
FORCEPROP 1 LAST VALUE 2.2K
J 2
(-750 3900);
DISPLAY 0.510638 (-750 3900);
PAINT SKYBLUE (-750 3900);
FORCEPROP 1 LAST PACK_TYPE 0402LF
J 0
(-375 3750);
DISPLAY 0.510638 (-375 3750);
PAINT SKYBLUE (-375 3750);
DISPLAY INVISIBLE (-375 3750);
FORCEPROP 1 LAST WATTAGE 1/16W
J 2
(-650 3750);
DISPLAY 0.510638 (-650 3750);
PAINT SKYBLUE (-650 3750);
DISPLAY INVISIBLE (-650 3750);
FORCEPROP 1 LAST PART_NUMBER CS22202JB07
J 0
(-675 4000);
DISPLAY 0.510638 (-675 4000);
PAINT WHITE (-675 4000);
DISPLAY INVISIBLE (-675 4000);
FORCEPROP 1 LAST TOLERANCE 5%
J 0
(-625 3800);
DISPLAY 0.510638 (-625 3800);
PAINT SKYBLUE (-625 3800);
DISPLAY INVISIBLE (-625 3800);
FORCEPROP 1 LAST PATH I242
J 0
(-675 4050);
DISPLAY 0.978723 (-675 4050);
PAINT WHITE (-675 4050);
DISPLAY INVISIBLE (-675 4050);
FORCEPROP 2 LAST CDS_LIB pure_quanta
J 0
(-625 3900);
DISPLAY INVISIBLE (-625 3900);
FORCEPROP 1 LAST LOCATION R438
J 0
(-975 3900);
DISPLAY 0.702128 (-975 3900);
PAINT YELLOW (-975 3900);
FORCEPROP 1 LASTPIN (-725 3900) $PN 1
J 0
(-713 3912);
DISPLAY 0.787234 (-713 3912);
PAINT MONO (-713 3912);
FORCEPROP 1 LASTPIN (-525 3900) $PN 2
J 0
(-563 3912);
DISPLAY 0.787234 (-563 3912);
PAINT MONO (-563 3912);
FORCEPROP 0 LAST $SEC 1
J 0
(-975 3950);
DISPLAY 0.680851 (-975 3950);
PAINT MONO (-975 3950);
DISPLAY INVISIBLE (-975 3950);
FORCEPROP 0 LAST CDS_SEC 1
J 0
(-975 3950);
DISPLAY 0.680851 (-975 3950);
DISPLAY INVISIBLE (-975 3950);
FORCEADD 2N7002A7..1
(3350 -700);
FORCEPROP 1 LAST MATERIAL IC
J 0
(3053 -370);
DISPLAY 0.723404 (3053 -370);
PAINT GREEN (3053 -370);
FORCEPROP 2 LAST PART_TYPE SMLF
J 0
(3075 -175);
DISPLAY 0.680851 (3075 -175);
FORCEPROP 1 LAST PART_NUMBER BAM70020068
J 0
(3053 -315);
DISPLAY 0.723404 (3053 -315);
PAINT GREEN (3053 -315);
FORCEPROP 2 LAST VALUE 2N7002A-7
J 0
(3075 -225);
DISPLAY 0.680851 (3075 -225);
FORCEPROP 2 LAST CDS_LIB pure_quanta
J 0
(3350 -700);
DISPLAY INVISIBLE (3350 -700);
FORCEPROP 1 LAST PATH I243
J 0
(3350 -700);
DISPLAY 0.723404 (3350 -700);
PAINT GREEN (3350 -700);
DISPLAY INVISIBLE (3350 -700);
FORCEPROP 1 LAST NEEDS_NO_SIZE TRUE
J 0
(3350 -700);
DISPLAY 0.723404 (3350 -700);
PAINT GREEN (3350 -700);
DISPLAY INVISIBLE (3350 -700);
FORCEPROP 1 LAST CDS_LMAN_SYM_OUTLINE -300,325,300,-325
J 0
(3350 -700);
DISPLAY 0.468085 (3350 -700);
PAINT GREEN (3350 -700);
DISPLAY INVISIBLE (3350 -700);
FORCEPROP 1 LAST LOCATION Q7
J 0
(3053 -265);
DISPLAY 0.723404 (3053 -265);
PAINT GREEN (3053 -265);
FORCEPROP 0 LASTPIN (2900 -425) $PN D
J 2
(2890 -415);
DISPLAY 0.680851 (2890 -415);
PAINT MONO (2890 -415);
FORCEPROP 0 LASTPIN (2900 -675) $PN G
J 2
(2890 -665);
DISPLAY 0.680851 (2890 -665);
PAINT MONO (2890 -665);
FORCEPROP 0 LASTPIN (3800 -925) $PN S
J 0
(3810 -915);
DISPLAY 0.680851 (3810 -915);
PAINT MONO (3810 -915);
FORCEPROP 0 LAST $SEC 1
J 0
(3075 -125);
DISPLAY 0.680851 (3075 -125);
PAINT MONO (3075 -125);
DISPLAY INVISIBLE (3075 -125);
FORCEPROP 0 LAST CDS_SEC 1
J 0
(3075 -125);
DISPLAY 0.680851 (3075 -125);
DISPLAY INVISIBLE (3075 -125);
FORCEADD Q_RES..2
(-2825 -1000);
FORCEPROP 1 LAST PACK_TYPE 0402LF
J 0
(-2785 -1175);
DISPLAY 0.510638 (-2785 -1175);
PAINT SKYBLUE (-2785 -1175);
FORCEPROP 1 LAST PART_NUMBER CS11002FB07
J 0
(-2785 -1125);
DISPLAY 0.510638 (-2785 -1125);
PAINT WHITE (-2785 -1125);
FORCEPROP 1 LAST TOLERANCE 1%
J 0
(-2780 -975);
DISPLAY 0.510638 (-2780 -975);
PAINT SKYBLUE (-2780 -975);
FORCEPROP 1 LAST VALUE 100
J 0
(-2780 -925);
DISPLAY 0.510638 (-2780 -925);
PAINT SKYBLUE (-2780 -925);
FORCEPROP 1 LAST WATTAGE 1/16W
J 0
(-2785 -1025);
DISPLAY 0.510638 (-2785 -1025);
PAINT SKYBLUE (-2785 -1025);
FORCEPROP 1 LAST MATERIAL EMPTY
J 0
(-2785 -1075);
DISPLAY 0.510638 (-2785 -1075);
PAINT RED (-2785 -1075);
FORCEPROP 2 LAST CDS_LIB pure_quanta
J 0
(-2825 -1000);
DISPLAY INVISIBLE (-2825 -1000);
FORCEPROP 1 LAST PATH I244
J 0
(-2775 -825);
DISPLAY 0.978723 (-2775 -825);
PAINT WHITE (-2775 -825);
DISPLAY INVISIBLE (-2775 -825);
FORCEPROP 1 LAST $LOCATION R164
J 0
(-2780 -875);
DISPLAY 0.702128 (-2780 -875);
PAINT YELLOW (-2780 -875);
FORCEPROP 0 LAST CDS_LOCATION R164
J 0
(-2775 -825);
DISPLAY 0.680851 (-2775 -825);
DISPLAY INVISIBLE (-2775 -825);
FORCEPROP 0 LAST $SEC 1
J 0
(-2775 -825);
DISPLAY 0.680851 (-2775 -825);
PAINT MONO (-2775 -825);
DISPLAY INVISIBLE (-2775 -825);
FORCEPROP 0 LAST CDS_SEC 1
J 0
(-2775 -825);
DISPLAY 0.680851 (-2775 -825);
DISPLAY INVISIBLE (-2775 -825);
FORCEPROP 1 LASTPIN (-2825 -900) $PN 1
J 0
(-2820 -938);
DISPLAY 0.808511 (-2820 -938);
PAINT WHITE (-2820 -938);
DISPLAY INVISIBLE (-2820 -938);
FORCEPROP 1 LASTPIN (-2825 -1100) $PN 2
J 0
(-2820 -1090);
DISPLAY 0.808511 (-2820 -1090);
PAINT WHITE (-2820 -1090);
DISPLAY INVISIBLE (-2820 -1090);
FORCEADD UNIVERSAL_GND..1
R 2
(-2825 -1300);
FORCEPROP 3 LASTPIN (-2825 -1250) SIG_NAME GND\g
J 0
(-2815 -1240);
DISPLAY 0.659574 (-2815 -1240);
PAINT MONO (-2815 -1240);
DISPLAY INVISIBLE (-2815 -1240);
FORCEPROP 2 LAST CDS_LIB logical_power
J 0
(-2825 -1300);
DISPLAY INVISIBLE (-2825 -1300);
FORCEPROP 1 LAST HDL_POWER GND
J 1
(-2850 -1375);
DISPLAY 0.702128 (-2850 -1375);
PAINT GREEN (-2850 -1375);
DISPLAY INVISIBLE (-2850 -1375);
FORCEPROP 1 LAST PATH I245
J 2
(-2900 -1300);
DISPLAY 0.872340 (-2900 -1300);
PAINT AQUA (-2900 -1300);
DISPLAY INVISIBLE (-2900 -1300);
FORCEADD Q_RES..2
(-3325 -975);
FORCEPROP 1 LAST WATTAGE 1/16W
J 0
(-3275 -1050);
DISPLAY 0.510638 (-3275 -1050);
PAINT SKYBLUE (-3275 -1050);
FORCEPROP 1 LAST VALUE 4.7K
J 0
(-3275 -900);
DISPLAY 0.510638 (-3275 -900);
PAINT SKYBLUE (-3275 -900);
FORCEPROP 1 LAST TOLERANCE 1%
J 0
(-3275 -950);
DISPLAY 0.510638 (-3275 -950);
PAINT SKYBLUE (-3275 -950);
FORCEPROP 1 LAST PACK_TYPE 0402LF
J 0
(-3275 -1000);
DISPLAY 0.510638 (-3275 -1000);
PAINT SKYBLUE (-3275 -1000);
FORCEPROP 1 LAST MATERIAL CHIP
J 0
(-3275 -1100);
DISPLAY 0.510638 (-3275 -1100);
PAINT SKYBLUE (-3275 -1100);
FORCEPROP 1 LAST PART_NUMBER CS24702FB06
J 0
(-3280 -1100);
DISPLAY 0.510638 (-3280 -1100);
PAINT WHITE (-3280 -1100);
DISPLAY INVISIBLE (-3280 -1100);
FORCEPROP 1 LAST PATH I246
J 0
(-3275 -800);
DISPLAY 0.978723 (-3275 -800);
PAINT WHITE (-3275 -800);
DISPLAY INVISIBLE (-3275 -800);
FORCEPROP 2 LAST CDS_LIB pure_quanta
J 0
(-3325 -975);
DISPLAY INVISIBLE (-3325 -975);
FORCEPROP 1 LAST LOCATION R94
J 0
(-3280 -850);
DISPLAY 0.702128 (-3280 -850);
PAINT YELLOW (-3280 -850);
FORCEPROP 1 LASTPIN (-3325 -875) $PN 1
J 0
(-3320 -913);
DISPLAY 0.787234 (-3320 -913);
PAINT MONO (-3320 -913);
FORCEPROP 1 LASTPIN (-3325 -1075) $PN 2
J 0
(-3320 -1065);
DISPLAY 0.787234 (-3320 -1065);
PAINT MONO (-3320 -1065);
FORCEPROP 0 LAST $SEC 1
J 0
(-3275 -800);
DISPLAY 0.680851 (-3275 -800);
PAINT MONO (-3275 -800);
DISPLAY INVISIBLE (-3275 -800);
FORCEPROP 0 LAST CDS_SEC 1
J 0
(-3275 -800);
DISPLAY 0.680851 (-3275 -800);
DISPLAY INVISIBLE (-3275 -800);
FORCEADD Q_RES..1
(-3625 3475);
FORCEPROP 1 LAST VALUE 499
J 2
(-3750 3475);
DISPLAY 0.510638 (-3750 3475);
PAINT SKYBLUE (-3750 3475);
FORCEPROP 1 LAST PART_NUMBER CS14992FB06
J 0
(-3375 3475);
DISPLAY 0.510638 (-3375 3475);
PAINT SKYBLUE (-3375 3475);
FORCEPROP 1 LAST MATERIAL CHIP
J 0
(-3500 3475);
DISPLAY 0.510638 (-3500 3475);
PAINT SKYBLUE (-3500 3475);
FORCEPROP 2 LAST CDS_LIB pure_quanta
J 0
(-3625 3475);
DISPLAY INVISIBLE (-3625 3475);
FORCEPROP 1 LAST PATH I247
J 0
(-3675 3625);
DISPLAY 0.978723 (-3675 3625);
PAINT WHITE (-3675 3625);
DISPLAY INVISIBLE (-3675 3625);
FORCEPROP 1 LAST WATTAGE 1/16W
J 2
(-3650 3325);
DISPLAY 0.510638 (-3650 3325);
DISPLAY INVISIBLE (-3650 3325);
FORCEPROP 1 LAST TOLERANCE 1%
J 0
(-3625 3375);
DISPLAY 0.510638 (-3625 3375);
DISPLAY INVISIBLE (-3625 3375);
FORCEPROP 1 LAST PACK_TYPE 0402LF
J 0
(-3375 3325);
DISPLAY 0.510638 (-3375 3325);
DISPLAY INVISIBLE (-3375 3325);
FORCEPROP 1 LAST LOCATION R251
J 0
(-3975 3475);
DISPLAY 0.638298 (-3975 3475);
PAINT YELLOW (-3975 3475);
FORCEPROP 1 LASTPIN (-3725 3475) $PN 1
J 0
(-3713 3487);
DISPLAY 0.787234 (-3713 3487);
PAINT MONO (-3713 3487);
FORCEPROP 1 LASTPIN (-3525 3475) $PN 2
J 0
(-3563 3487);
DISPLAY 0.787234 (-3563 3487);
PAINT MONO (-3563 3487);
FORCEPROP 0 LAST $SEC 1
J 0
(-3975 3525);
DISPLAY 0.680851 (-3975 3525);
PAINT MONO (-3975 3525);
DISPLAY INVISIBLE (-3975 3525);
FORCEPROP 0 LAST CDS_SEC 1
J 0
(-3975 3525);
DISPLAY 0.680851 (-3975 3525);
DISPLAY INVISIBLE (-3975 3525);
FORCEADD OFFPAGE..2
(-1875 3275);
FORCEPROP 2 LAST $XR0 12 
J 0
(-1686 3275);
DISPLAY 0.638298 (-1686 3275);
PAINT MONO (-1686 3275);
FORCEPROP 2 LAST PATH I75
J 0
(-1625 3325);
DISPLAY 1.021277 (-1625 3325);
DISPLAY INVISIBLE (-1625 3325);
FORCEPROP 1 LAST COMMENT_BODY TRUE
J 0
(-1920 3180);
DISPLAY 0.872340 (-1920 3180);
PAINT PEACH (-1920 3180);
DISPLAY INVISIBLE (-1920 3180);
FORCEPROP 1 LAST OFFPAGE TRUE
J 0
(-1550 3150);
DISPLAY 0.872340 (-1550 3150);
PAINT GREEN (-1550 3150);
DISPLAY INVISIBLE (-1550 3150);
FORCEPROP 2 LAST CDS_LIB standard
J 0
(-1875 3275);
DISPLAY INVISIBLE (-1875 3275);
FORCEADD Q_RES..1
(-3625 1125);
FORCEPROP 1 LAST VALUE 4.7K
J 2
(-3750 1125);
DISPLAY 0.510638 (-3750 1125);
PAINT SKYBLUE (-3750 1125);
FORCEPROP 1 LAST MATERIAL CHIP
J 0
(-3500 1125);
DISPLAY 0.510638 (-3500 1125);
PAINT SKYBLUE (-3500 1125);
FORCEPROP 2 LAST CDS_LIB pure_quanta
J 0
(-3625 1125);
DISPLAY INVISIBLE (-3625 1125);
FORCEPROP 1 LAST TOLERANCE 1%
J 0
(-3625 1025);
DISPLAY 0.510638 (-3625 1025);
PAINT SKYBLUE (-3625 1025);
DISPLAY INVISIBLE (-3625 1025);
FORCEPROP 1 LAST PATH I84
J 0
(-3675 1275);
DISPLAY 0.978723 (-3675 1275);
PAINT WHITE (-3675 1275);
DISPLAY INVISIBLE (-3675 1275);
FORCEPROP 1 LAST WATTAGE 1/16W
J 2
(-3650 975);
DISPLAY 0.510638 (-3650 975);
PAINT SKYBLUE (-3650 975);
DISPLAY INVISIBLE (-3650 975);
FORCEPROP 1 LAST PACK_TYPE 0402LF
J 0
(-3375 975);
DISPLAY 0.510638 (-3375 975);
PAINT SKYBLUE (-3375 975);
DISPLAY INVISIBLE (-3375 975);
FORCEPROP 1 LAST PART_NUMBER CS24702FB06
J 0
(-3675 1225);
DISPLAY 0.510638 (-3675 1225);
PAINT WHITE (-3675 1225);
DISPLAY INVISIBLE (-3675 1225);
FORCEPROP 1 LAST LOCATION R269
J 0
(-3975 1125);
DISPLAY 0.702128 (-3975 1125);
PAINT YELLOW (-3975 1125);
FORCEPROP 0 LAST $SEC 1
J 0
(-3900 1175);
DISPLAY INVISIBLE (-3900 1175);
FORCEPROP 0 LAST CDS_SEC 1
J 0
(-3900 1175);
DISPLAY INVISIBLE (-3900 1175);
FORCEPROP 1 LASTPIN (-3725 1125) $PN 1
J 0
(-3713 1137);
DISPLAY 0.808511 (-3713 1137);
PAINT WHITE (-3713 1137);
DISPLAY INVISIBLE (-3713 1137);
FORCEPROP 1 LASTPIN (-3525 1125) $PN 2
J 0
(-3563 1137);
DISPLAY 0.808511 (-3563 1137);
PAINT WHITE (-3563 1137);
DISPLAY INVISIBLE (-3563 1137);
FORCEADD Q_RES..1
(-3625 1275);
FORCEPROP 1 LAST VALUE 4.7K
J 2
(-3750 1275);
DISPLAY 0.510638 (-3750 1275);
PAINT SKYBLUE (-3750 1275);
FORCEPROP 1 LAST MATERIAL EMPTY
J 0
(-3500 1275);
DISPLAY 0.510638 (-3500 1275);
PAINT RED (-3500 1275);
FORCEPROP 2 LAST CDS_LIB pure_quanta
J 0
(-3625 1275);
DISPLAY INVISIBLE (-3625 1275);
FORCEPROP 1 LAST TOLERANCE 1%
J 0
(-3625 1175);
DISPLAY 0.510638 (-3625 1175);
PAINT SKYBLUE (-3625 1175);
DISPLAY INVISIBLE (-3625 1175);
FORCEPROP 1 LAST PATH I85
J 0
(-3675 1425);
DISPLAY 0.978723 (-3675 1425);
PAINT WHITE (-3675 1425);
DISPLAY INVISIBLE (-3675 1425);
FORCEPROP 1 LAST WATTAGE 1/16W
J 2
(-3650 1125);
DISPLAY 0.510638 (-3650 1125);
PAINT SKYBLUE (-3650 1125);
DISPLAY INVISIBLE (-3650 1125);
FORCEPROP 1 LAST PACK_TYPE 0402LF
J 0
(-3375 1125);
DISPLAY 0.510638 (-3375 1125);
PAINT SKYBLUE (-3375 1125);
DISPLAY INVISIBLE (-3375 1125);
FORCEPROP 1 LAST PART_NUMBER CS24702FB06
J 0
(-3675 1375);
DISPLAY 0.510638 (-3675 1375);
PAINT WHITE (-3675 1375);
DISPLAY INVISIBLE (-3675 1375);
FORCEPROP 1 LAST LOCATION R267
J 0
(-3975 1275);
DISPLAY 0.702128 (-3975 1275);
PAINT YELLOW (-3975 1275);
FORCEPROP 0 LAST $SEC 1
J 0
(-3900 1325);
DISPLAY INVISIBLE (-3900 1325);
FORCEPROP 0 LAST CDS_SEC 1
J 0
(-3900 1325);
DISPLAY INVISIBLE (-3900 1325);
FORCEPROP 1 LASTPIN (-3725 1275) $PN 1
J 0
(-3713 1287);
DISPLAY 0.808511 (-3713 1287);
PAINT WHITE (-3713 1287);
DISPLAY INVISIBLE (-3713 1287);
FORCEPROP 1 LASTPIN (-3525 1275) $PN 2
J 0
(-3563 1287);
DISPLAY 0.808511 (-3563 1287);
PAINT WHITE (-3563 1287);
DISPLAY INVISIBLE (-3563 1287);
FORCEADD Q_RES..1
(-3625 1200);
FORCEPROP 1 LAST MATERIAL CHIP
J 0
(-3500 1200);
DISPLAY 0.510638 (-3500 1200);
PAINT SKYBLUE (-3500 1200);
FORCEPROP 1 LAST VALUE 4.7K
J 2
(-3750 1200);
DISPLAY 0.510638 (-3750 1200);
PAINT SKYBLUE (-3750 1200);
FORCEPROP 2 LAST CDS_LIB pure_quanta
J 0
(-3625 1200);
DISPLAY INVISIBLE (-3625 1200);
FORCEPROP 1 LAST TOLERANCE 1%
J 0
(-3625 1100);
DISPLAY 0.510638 (-3625 1100);
PAINT SKYBLUE (-3625 1100);
DISPLAY INVISIBLE (-3625 1100);
FORCEPROP 1 LAST PATH I86
J 0
(-3675 1350);
DISPLAY 0.978723 (-3675 1350);
PAINT WHITE (-3675 1350);
DISPLAY INVISIBLE (-3675 1350);
FORCEPROP 1 LAST WATTAGE 1/16W
J 2
(-3650 1050);
DISPLAY 0.510638 (-3650 1050);
PAINT SKYBLUE (-3650 1050);
DISPLAY INVISIBLE (-3650 1050);
FORCEPROP 1 LAST PACK_TYPE 0402LF
J 0
(-3375 1050);
DISPLAY 0.510638 (-3375 1050);
PAINT SKYBLUE (-3375 1050);
DISPLAY INVISIBLE (-3375 1050);
FORCEPROP 1 LAST PART_NUMBER CS24702FB06
J 0
(-3675 1300);
DISPLAY 0.510638 (-3675 1300);
PAINT WHITE (-3675 1300);
DISPLAY INVISIBLE (-3675 1300);
FORCEPROP 1 LAST LOCATION R268
J 0
(-3975 1200);
DISPLAY 0.702128 (-3975 1200);
PAINT YELLOW (-3975 1200);
FORCEPROP 0 LAST $SEC 1
J 0
(-3900 1250);
DISPLAY INVISIBLE (-3900 1250);
FORCEPROP 0 LAST CDS_SEC 1
J 0
(-3900 1250);
DISPLAY INVISIBLE (-3900 1250);
FORCEPROP 1 LASTPIN (-3725 1200) $PN 1
J 0
(-3713 1212);
DISPLAY 0.808511 (-3713 1212);
PAINT WHITE (-3713 1212);
DISPLAY INVISIBLE (-3713 1212);
FORCEPROP 1 LASTPIN (-3525 1200) $PN 2
J 0
(-3563 1212);
DISPLAY 0.808511 (-3563 1212);
PAINT WHITE (-3563 1212);
DISPLAY INVISIBLE (-3563 1212);
FORCEADD UNIVERSAL_POWER..1
(-4075 1500);
FORCEPROP 3 LASTPIN (-4075 1450) SIG_NAME P3V3_AUX\g
J 0
(-4065 1460);
DISPLAY 0.659574 (-4065 1460);
PAINT MONO (-4065 1460);
DISPLAY INVISIBLE (-4065 1460);
FORCEPROP 1 LAST HDL_POWER P3V3_AUX
J 1
(-4075 1550);
DISPLAY 0.702128 (-4075 1550);
PAINT GREEN (-4075 1550);
FORCEPROP 2 LAST CDS_LIB logical_power
J 0
(-4075 1500);
DISPLAY INVISIBLE (-4075 1500);
FORCEPROP 1 LAST PATH I87
J 0
(-4025 1525);
DISPLAY 0.872340 (-4025 1525);
PAINT AQUA (-4025 1525);
DISPLAY INVISIBLE (-4025 1525);
FORCEADD Q_RES..1
(-3625 1675);
FORCEPROP 1 LAST VALUE 2.2K
J 2
(-3750 1675);
DISPLAY 0.510638 (-3750 1675);
PAINT SKYBLUE (-3750 1675);
FORCEPROP 1 LAST MATERIAL CHIP
J 0
(-3500 1675);
DISPLAY 0.510638 (-3500 1675);
PAINT SKYBLUE (-3500 1675);
FORCEPROP 1 LAST TOLERANCE 5%
J 0
(-3625 1575);
DISPLAY 0.510638 (-3625 1575);
PAINT SKYBLUE (-3625 1575);
DISPLAY INVISIBLE (-3625 1575);
FORCEPROP 1 LAST PART_NUMBER CS22202JB07
J 0
(-3675 1775);
DISPLAY 0.510638 (-3675 1775);
PAINT WHITE (-3675 1775);
DISPLAY INVISIBLE (-3675 1775);
FORCEPROP 1 LAST PACK_TYPE 0402LF
J 0
(-3375 1525);
DISPLAY 0.510638 (-3375 1525);
PAINT SKYBLUE (-3375 1525);
DISPLAY INVISIBLE (-3375 1525);
FORCEPROP 1 LAST WATTAGE 1/16W
J 2
(-3650 1525);
DISPLAY 0.510638 (-3650 1525);
PAINT SKYBLUE (-3650 1525);
DISPLAY INVISIBLE (-3650 1525);
FORCEPROP 1 LAST PATH I88
J 0
(-3675 1825);
DISPLAY 0.978723 (-3675 1825);
PAINT WHITE (-3675 1825);
DISPLAY INVISIBLE (-3675 1825);
FORCEPROP 2 LAST CDS_LIB pure_quanta
J 0
(-3625 1675);
DISPLAY INVISIBLE (-3625 1675);
FORCEPROP 1 LAST LOCATION R265
J 0
(-3975 1675);
DISPLAY 0.702128 (-3975 1675);
PAINT YELLOW (-3975 1675);
FORCEPROP 0 LAST $SEC 1
J 0
(-3900 1725);
DISPLAY INVISIBLE (-3900 1725);
FORCEPROP 0 LAST CDS_SEC 1
J 0
(-3900 1725);
DISPLAY INVISIBLE (-3900 1725);
FORCEPROP 1 LASTPIN (-3725 1675) $PN 1
J 0
(-3713 1687);
DISPLAY 0.808511 (-3713 1687);
PAINT WHITE (-3713 1687);
DISPLAY INVISIBLE (-3713 1687);
FORCEPROP 1 LASTPIN (-3525 1675) $PN 2
J 0
(-3563 1687);
DISPLAY 0.808511 (-3563 1687);
PAINT WHITE (-3563 1687);
DISPLAY INVISIBLE (-3563 1687);
FORCEADD Q_RES..1
(-3625 1775);
FORCEPROP 1 LAST MATERIAL CHIP
J 0
(-3500 1775);
DISPLAY 0.510638 (-3500 1775);
PAINT SKYBLUE (-3500 1775);
FORCEPROP 1 LAST VALUE 2.2K
J 2
(-3750 1775);
DISPLAY 0.510638 (-3750 1775);
PAINT SKYBLUE (-3750 1775);
FORCEPROP 1 LAST TOLERANCE 5%
J 0
(-3625 1675);
DISPLAY 0.510638 (-3625 1675);
PAINT SKYBLUE (-3625 1675);
DISPLAY INVISIBLE (-3625 1675);
FORCEPROP 1 LAST PART_NUMBER CS22202JB07
J 0
(-3675 1875);
DISPLAY 0.510638 (-3675 1875);
PAINT WHITE (-3675 1875);
DISPLAY INVISIBLE (-3675 1875);
FORCEPROP 1 LAST PACK_TYPE 0402LF
J 0
(-3375 1625);
DISPLAY 0.510638 (-3375 1625);
PAINT SKYBLUE (-3375 1625);
DISPLAY INVISIBLE (-3375 1625);
FORCEPROP 1 LAST WATTAGE 1/16W
J 2
(-3650 1625);
DISPLAY 0.510638 (-3650 1625);
PAINT SKYBLUE (-3650 1625);
DISPLAY INVISIBLE (-3650 1625);
FORCEPROP 1 LAST PATH I89
J 0
(-3675 1925);
DISPLAY 0.978723 (-3675 1925);
PAINT WHITE (-3675 1925);
DISPLAY INVISIBLE (-3675 1925);
FORCEPROP 2 LAST CDS_LIB pure_quanta
J 0
(-3625 1775);
DISPLAY INVISIBLE (-3625 1775);
FORCEPROP 1 LAST LOCATION R264
J 0
(-3975 1775);
DISPLAY 0.702128 (-3975 1775);
PAINT YELLOW (-3975 1775);
FORCEPROP 0 LAST $SEC 1
J 0
(-3900 1825);
DISPLAY INVISIBLE (-3900 1825);
FORCEPROP 0 LAST CDS_SEC 1
J 0
(-3900 1825);
DISPLAY INVISIBLE (-3900 1825);
FORCEPROP 1 LASTPIN (-3725 1775) $PN 1
J 0
(-3713 1787);
DISPLAY 0.808511 (-3713 1787);
PAINT WHITE (-3713 1787);
DISPLAY INVISIBLE (-3713 1787);
FORCEPROP 1 LASTPIN (-3525 1775) $PN 2
J 0
(-3563 1787);
DISPLAY 0.808511 (-3563 1787);
PAINT WHITE (-3563 1787);
DISPLAY INVISIBLE (-3563 1787);
FORCEADD Q_RES..1
(-3625 2375);
FORCEPROP 1 LAST VALUE 10K
J 2
(-3750 2375);
DISPLAY 0.510638 (-3750 2375);
PAINT SKYBLUE (-3750 2375);
FORCEPROP 1 LAST MATERIAL CHIP
J 0
(-3500 2375);
DISPLAY 0.510638 (-3500 2375);
PAINT SKYBLUE (-3500 2375);
FORCEPROP 1 LAST PART_NUMBER CS31002FB08
J 0
(-3675 2475);
DISPLAY 0.510638 (-3675 2475);
PAINT WHITE (-3675 2475);
DISPLAY INVISIBLE (-3675 2475);
FORCEPROP 1 LAST TOLERANCE 1%
J 0
(-3625 2275);
DISPLAY 0.510638 (-3625 2275);
PAINT SKYBLUE (-3625 2275);
DISPLAY INVISIBLE (-3625 2275);
FORCEPROP 1 LAST WATTAGE 1/16W
J 2
(-3650 2225);
DISPLAY 0.510638 (-3650 2225);
PAINT SKYBLUE (-3650 2225);
DISPLAY INVISIBLE (-3650 2225);
FORCEPROP 1 LAST PACK_TYPE 0402LF
J 0
(-3375 2225);
DISPLAY 0.510638 (-3375 2225);
PAINT SKYBLUE (-3375 2225);
DISPLAY INVISIBLE (-3375 2225);
FORCEPROP 1 LAST PATH I93
J 0
(-3675 2525);
DISPLAY 0.978723 (-3675 2525);
PAINT WHITE (-3675 2525);
DISPLAY INVISIBLE (-3675 2525);
FORCEPROP 2 LAST CDS_LIB pure_quanta
J 0
(-3625 2375);
DISPLAY INVISIBLE (-3625 2375);
FORCEPROP 1 LAST LOCATION R262
J 0
(-3975 2375);
DISPLAY 0.702128 (-3975 2375);
PAINT YELLOW (-3975 2375);
FORCEPROP 0 LAST $SEC 1
J 0
(-3900 2425);
DISPLAY INVISIBLE (-3900 2425);
FORCEPROP 0 LAST CDS_SEC 1
J 0
(-3900 2425);
DISPLAY INVISIBLE (-3900 2425);
FORCEPROP 1 LASTPIN (-3725 2375) $PN 1
J 0
(-3713 2387);
DISPLAY 0.808511 (-3713 2387);
PAINT WHITE (-3713 2387);
DISPLAY INVISIBLE (-3713 2387);
FORCEPROP 1 LASTPIN (-3525 2375) $PN 2
J 0
(-3563 2387);
DISPLAY 0.808511 (-3563 2387);
PAINT WHITE (-3563 2387);
DISPLAY INVISIBLE (-3563 2387);
FORCEADD Q_RES..1
(-3625 2475);
FORCEPROP 1 LAST MATERIAL CHIP
J 0
(-3500 2475);
DISPLAY 0.510638 (-3500 2475);
PAINT SKYBLUE (-3500 2475);
FORCEPROP 1 LAST VALUE 10K
J 2
(-3750 2475);
DISPLAY 0.510638 (-3750 2475);
PAINT SKYBLUE (-3750 2475);
FORCEPROP 1 LAST PART_NUMBER CS31002FB08
J 0
(-3675 2575);
DISPLAY 0.510638 (-3675 2575);
PAINT WHITE (-3675 2575);
DISPLAY INVISIBLE (-3675 2575);
FORCEPROP 1 LAST TOLERANCE 1%
J 0
(-3625 2375);
DISPLAY 0.510638 (-3625 2375);
PAINT SKYBLUE (-3625 2375);
DISPLAY INVISIBLE (-3625 2375);
FORCEPROP 2 LAST CDS_LIB pure_quanta
J 0
(-3625 2475);
DISPLAY INVISIBLE (-3625 2475);
FORCEPROP 1 LAST PATH I94
J 0
(-3675 2625);
DISPLAY 0.978723 (-3675 2625);
PAINT WHITE (-3675 2625);
DISPLAY INVISIBLE (-3675 2625);
FORCEPROP 1 LAST WATTAGE 1/16W
J 2
(-3650 2325);
DISPLAY 0.510638 (-3650 2325);
PAINT SKYBLUE (-3650 2325);
DISPLAY INVISIBLE (-3650 2325);
FORCEPROP 1 LAST PACK_TYPE 0402LF
J 0
(-3375 2325);
DISPLAY 0.510638 (-3375 2325);
PAINT SKYBLUE (-3375 2325);
DISPLAY INVISIBLE (-3375 2325);
FORCEPROP 1 LAST LOCATION R261
J 0
(-3975 2475);
DISPLAY 0.702128 (-3975 2475);
PAINT YELLOW (-3975 2475);
FORCEPROP 0 LAST $SEC 1
J 0
(-3900 2525);
DISPLAY INVISIBLE (-3900 2525);
FORCEPROP 0 LAST CDS_SEC 1
J 0
(-3900 2525);
DISPLAY INVISIBLE (-3900 2525);
FORCEPROP 1 LASTPIN (-3725 2475) $PN 1
J 0
(-3713 2487);
DISPLAY 0.808511 (-3713 2487);
PAINT WHITE (-3713 2487);
DISPLAY INVISIBLE (-3713 2487);
FORCEPROP 1 LASTPIN (-3525 2475) $PN 2
J 0
(-3563 2487);
DISPLAY 0.808511 (-3563 2487);
PAINT WHITE (-3563 2487);
DISPLAY INVISIBLE (-3563 2487);
FORCEADD Q_RES..1
(-3625 1350);
FORCEPROP 1 LAST VALUE 4.7K
J 2
(-3750 1350);
DISPLAY 0.510638 (-3750 1350);
PAINT SKYBLUE (-3750 1350);
FORCEPROP 1 LAST MATERIAL EMPTY
J 0
(-3500 1350);
DISPLAY 0.510638 (-3500 1350);
PAINT RED (-3500 1350);
FORCEPROP 2 LAST CDS_LIB pure_quanta
J 0
(-3625 1350);
DISPLAY INVISIBLE (-3625 1350);
FORCEPROP 1 LAST TOLERANCE 1%
J 0
(-3625 1250);
DISPLAY 0.510638 (-3625 1250);
PAINT SKYBLUE (-3625 1250);
DISPLAY INVISIBLE (-3625 1250);
FORCEPROP 1 LAST PATH I95
J 0
(-3675 1500);
DISPLAY 0.978723 (-3675 1500);
PAINT WHITE (-3675 1500);
DISPLAY INVISIBLE (-3675 1500);
FORCEPROP 1 LAST WATTAGE 1/16W
J 2
(-3650 1200);
DISPLAY 0.510638 (-3650 1200);
PAINT SKYBLUE (-3650 1200);
DISPLAY INVISIBLE (-3650 1200);
FORCEPROP 1 LAST PACK_TYPE 0402LF
J 0
(-3375 1200);
DISPLAY 0.510638 (-3375 1200);
PAINT SKYBLUE (-3375 1200);
DISPLAY INVISIBLE (-3375 1200);
FORCEPROP 1 LAST PART_NUMBER CS24702FB06
J 0
(-3675 1450);
DISPLAY 0.510638 (-3675 1450);
PAINT WHITE (-3675 1450);
DISPLAY INVISIBLE (-3675 1450);
FORCEPROP 1 LAST LOCATION R266
J 0
(-3975 1350);
DISPLAY 0.702128 (-3975 1350);
PAINT YELLOW (-3975 1350);
FORCEPROP 0 LAST $SEC 1
J 0
(-3900 1400);
DISPLAY INVISIBLE (-3900 1400);
FORCEPROP 0 LAST CDS_SEC 1
J 0
(-3900 1400);
DISPLAY INVISIBLE (-3900 1400);
FORCEPROP 1 LASTPIN (-3725 1350) $PN 1
J 0
(-3713 1362);
DISPLAY 0.808511 (-3713 1362);
PAINT WHITE (-3713 1362);
DISPLAY INVISIBLE (-3713 1362);
FORCEPROP 1 LASTPIN (-3525 1350) $PN 2
J 0
(-3563 1362);
DISPLAY 0.808511 (-3563 1362);
PAINT WHITE (-3563 1362);
DISPLAY INVISIBLE (-3563 1362);
FORCEADD Q_RES..1
(-3625 2675);
FORCEPROP 1 LAST MATERIAL CHIP
J 0
(-3500 2675);
DISPLAY 0.510638 (-3500 2675);
PAINT SKYBLUE (-3500 2675);
FORCEPROP 1 LAST VALUE 2.2K
J 2
(-3750 2675);
DISPLAY 0.510638 (-3750 2675);
PAINT SKYBLUE (-3750 2675);
FORCEPROP 1 LAST TOLERANCE 5%
J 0
(-3625 2575);
DISPLAY 0.510638 (-3625 2575);
PAINT SKYBLUE (-3625 2575);
DISPLAY INVISIBLE (-3625 2575);
FORCEPROP 1 LAST PART_NUMBER CS22202JB07
J 0
(-3675 2775);
DISPLAY 0.510638 (-3675 2775);
PAINT WHITE (-3675 2775);
DISPLAY INVISIBLE (-3675 2775);
FORCEPROP 1 LAST PACK_TYPE 0402LF
J 0
(-3375 2525);
DISPLAY 0.510638 (-3375 2525);
PAINT SKYBLUE (-3375 2525);
DISPLAY INVISIBLE (-3375 2525);
FORCEPROP 1 LAST WATTAGE 1/16W
J 2
(-3650 2525);
DISPLAY 0.510638 (-3650 2525);
PAINT SKYBLUE (-3650 2525);
DISPLAY INVISIBLE (-3650 2525);
FORCEPROP 1 LAST PATH I96
J 0
(-3675 2825);
DISPLAY 0.978723 (-3675 2825);
PAINT WHITE (-3675 2825);
DISPLAY INVISIBLE (-3675 2825);
FORCEPROP 2 LAST CDS_LIB pure_quanta
J 0
(-3625 2675);
DISPLAY INVISIBLE (-3625 2675);
FORCEPROP 1 LAST LOCATION R259
J 0
(-3975 2675);
DISPLAY 0.702128 (-3975 2675);
PAINT YELLOW (-3975 2675);
FORCEPROP 0 LAST $SEC 1
J 0
(-3900 2725);
DISPLAY INVISIBLE (-3900 2725);
FORCEPROP 0 LAST CDS_SEC 1
J 0
(-3900 2725);
DISPLAY INVISIBLE (-3900 2725);
FORCEPROP 1 LASTPIN (-3725 2675) $PN 1
J 0
(-3713 2687);
DISPLAY 0.808511 (-3713 2687);
PAINT WHITE (-3713 2687);
DISPLAY INVISIBLE (-3713 2687);
FORCEPROP 1 LASTPIN (-3525 2675) $PN 2
J 0
(-3563 2687);
DISPLAY 0.808511 (-3563 2687);
PAINT WHITE (-3563 2687);
DISPLAY INVISIBLE (-3563 2687);
FORCEADD Q_RES..1
(-3625 2575);
FORCEPROP 1 LAST VALUE 10K
J 2
(-3750 2575);
DISPLAY 0.510638 (-3750 2575);
PAINT SKYBLUE (-3750 2575);
FORCEPROP 1 LAST MATERIAL CHIP
J 0
(-3500 2575);
DISPLAY 0.510638 (-3500 2575);
PAINT SKYBLUE (-3500 2575);
FORCEPROP 1 LAST PART_NUMBER CS31002FB08
J 0
(-3675 2675);
DISPLAY 0.510638 (-3675 2675);
PAINT WHITE (-3675 2675);
DISPLAY INVISIBLE (-3675 2675);
FORCEPROP 1 LAST TOLERANCE 1%
J 0
(-3625 2475);
DISPLAY 0.510638 (-3625 2475);
PAINT SKYBLUE (-3625 2475);
DISPLAY INVISIBLE (-3625 2475);
FORCEPROP 2 LAST CDS_LIB pure_quanta
J 0
(-3625 2575);
DISPLAY INVISIBLE (-3625 2575);
FORCEPROP 1 LAST PATH I97
J 0
(-3675 2725);
DISPLAY 0.978723 (-3675 2725);
PAINT WHITE (-3675 2725);
DISPLAY INVISIBLE (-3675 2725);
FORCEPROP 1 LAST WATTAGE 1/16W
J 2
(-3650 2425);
DISPLAY 0.510638 (-3650 2425);
PAINT SKYBLUE (-3650 2425);
DISPLAY INVISIBLE (-3650 2425);
FORCEPROP 1 LAST PACK_TYPE 0402LF
J 0
(-3375 2425);
DISPLAY 0.510638 (-3375 2425);
PAINT SKYBLUE (-3375 2425);
DISPLAY INVISIBLE (-3375 2425);
FORCEPROP 1 LAST LOCATION R260
J 0
(-3975 2575);
DISPLAY 0.702128 (-3975 2575);
PAINT YELLOW (-3975 2575);
FORCEPROP 0 LAST $SEC 1
J 0
(-3900 2625);
DISPLAY INVISIBLE (-3900 2625);
FORCEPROP 0 LAST CDS_SEC 1
J 0
(-3900 2625);
DISPLAY INVISIBLE (-3900 2625);
FORCEPROP 1 LASTPIN (-3725 2575) $PN 1
J 0
(-3713 2587);
DISPLAY 0.808511 (-3713 2587);
PAINT WHITE (-3713 2587);
DISPLAY INVISIBLE (-3713 2587);
FORCEPROP 1 LASTPIN (-3525 2575) $PN 2
J 0
(-3563 2587);
DISPLAY 0.808511 (-3563 2587);
PAINT WHITE (-3563 2587);
DISPLAY INVISIBLE (-3563 2587);
FORCEADD Q_RES..1
(-3625 2775);
FORCEPROP 1 LAST MATERIAL CHIP
J 0
(-3500 2775);
DISPLAY 0.510638 (-3500 2775);
PAINT SKYBLUE (-3500 2775);
FORCEPROP 1 LAST VALUE 2.2K
J 2
(-3750 2775);
DISPLAY 0.510638 (-3750 2775);
PAINT SKYBLUE (-3750 2775);
FORCEPROP 1 LAST TOLERANCE 5%
J 0
(-3625 2675);
DISPLAY 0.510638 (-3625 2675);
PAINT SKYBLUE (-3625 2675);
DISPLAY INVISIBLE (-3625 2675);
FORCEPROP 1 LAST PART_NUMBER CS22202JB07
J 0
(-3675 2875);
DISPLAY 0.510638 (-3675 2875);
PAINT WHITE (-3675 2875);
DISPLAY INVISIBLE (-3675 2875);
FORCEPROP 1 LAST PACK_TYPE 0402LF
J 0
(-3375 2625);
DISPLAY 0.510638 (-3375 2625);
PAINT SKYBLUE (-3375 2625);
DISPLAY INVISIBLE (-3375 2625);
FORCEPROP 1 LAST WATTAGE 1/16W
J 2
(-3650 2625);
DISPLAY 0.510638 (-3650 2625);
PAINT SKYBLUE (-3650 2625);
DISPLAY INVISIBLE (-3650 2625);
FORCEPROP 1 LAST PATH I98
J 0
(-3675 2925);
DISPLAY 0.978723 (-3675 2925);
PAINT WHITE (-3675 2925);
DISPLAY INVISIBLE (-3675 2925);
FORCEPROP 2 LAST CDS_LIB pure_quanta
J 0
(-3625 2775);
DISPLAY INVISIBLE (-3625 2775);
FORCEPROP 1 LAST LOCATION R258
J 0
(-3975 2775);
DISPLAY 0.702128 (-3975 2775);
PAINT YELLOW (-3975 2775);
FORCEPROP 0 LAST $SEC 1
J 0
(-3900 2825);
DISPLAY INVISIBLE (-3900 2825);
FORCEPROP 0 LAST CDS_SEC 1
J 0
(-3900 2825);
DISPLAY INVISIBLE (-3900 2825);
FORCEPROP 1 LASTPIN (-3725 2775) $PN 1
J 0
(-3713 2787);
DISPLAY 0.808511 (-3713 2787);
PAINT WHITE (-3713 2787);
DISPLAY INVISIBLE (-3713 2787);
FORCEPROP 1 LASTPIN (-3525 2775) $PN 2
J 0
(-3563 2787);
DISPLAY 0.808511 (-3563 2787);
PAINT WHITE (-3563 2787);
DISPLAY INVISIBLE (-3563 2787);
FORCEADD Q_RES..1
(-3625 2875);
FORCEPROP 1 LAST VALUE 2.2K
J 2
(-3750 2875);
DISPLAY 0.510638 (-3750 2875);
PAINT SKYBLUE (-3750 2875);
FORCEPROP 1 LAST MATERIAL CHIP
J 0
(-3500 2875);
DISPLAY 0.510638 (-3500 2875);
PAINT SKYBLUE (-3500 2875);
FORCEPROP 1 LAST TOLERANCE 5%
J 0
(-3625 2775);
DISPLAY 0.510638 (-3625 2775);
PAINT SKYBLUE (-3625 2775);
DISPLAY INVISIBLE (-3625 2775);
FORCEPROP 1 LAST PART_NUMBER CS22202JB07
J 0
(-3675 2975);
DISPLAY 0.510638 (-3675 2975);
PAINT WHITE (-3675 2975);
DISPLAY INVISIBLE (-3675 2975);
FORCEPROP 1 LAST PACK_TYPE 0402LF
J 0
(-3375 2725);
DISPLAY 0.510638 (-3375 2725);
PAINT SKYBLUE (-3375 2725);
DISPLAY INVISIBLE (-3375 2725);
FORCEPROP 1 LAST WATTAGE 1/16W
J 2
(-3650 2725);
DISPLAY 0.510638 (-3650 2725);
PAINT SKYBLUE (-3650 2725);
DISPLAY INVISIBLE (-3650 2725);
FORCEPROP 1 LAST PATH I99
J 0
(-3675 3025);
DISPLAY 0.978723 (-3675 3025);
PAINT WHITE (-3675 3025);
DISPLAY INVISIBLE (-3675 3025);
FORCEPROP 2 LAST CDS_LIB pure_quanta
J 0
(-3625 2875);
DISPLAY INVISIBLE (-3625 2875);
FORCEPROP 1 LAST LOCATION R257
J 0
(-3975 2875);
DISPLAY 0.702128 (-3975 2875);
PAINT YELLOW (-3975 2875);
FORCEPROP 0 LAST $SEC 1
J 0
(-3900 2925);
DISPLAY INVISIBLE (-3900 2925);
FORCEPROP 0 LAST CDS_SEC 1
J 0
(-3900 2925);
DISPLAY INVISIBLE (-3900 2925);
FORCEPROP 1 LASTPIN (-3725 2875) $PN 1
J 0
(-3713 2887);
DISPLAY 0.808511 (-3713 2887);
PAINT WHITE (-3713 2887);
DISPLAY INVISIBLE (-3713 2887);
FORCEPROP 1 LASTPIN (-3525 2875) $PN 2
J 0
(-3563 2887);
DISPLAY 0.808511 (-3563 2887);
PAINT WHITE (-3563 2887);
DISPLAY INVISIBLE (-3563 2887);
FORCEADD QUANTA_TITLE_BLOCK_C..1
(4675 -1925);
FORCEPROP 0 LAST CDS_CON_LAST_MODIFIED Fri Aug 25 17:25:41 2023
J 0
(2790 -1910);
DISPLAY INVISIBLE (2790 -1910);
FORCEPROP 2 LAST Q_DEPT 
J 1
(912 -1876);
DISPLAY 1.957447 (912 -1876);
PAINT GREEN (912 -1876);
FORCEPROP 1 LAST CUSTOM_TXT_CDS <CON_LAST_MODIFIED>
J 0
(2790 -1910);
DISPLAY 0.978723 (2790 -1910);
FORCEPROP 2 LAST CUSTOM_TXT_CDS <XR_PAGE_TITLE>
J 0
(-3215 3325);
DISPLAY 0.638298 (-3215 3325);
PAINT PINK (-3215 3325);
DISPLAY INVISIBLE (-3215 3325);
FORCEPROP 1 LAST CUSTOM_TXT_CDS <NAME_2>
J 0
(1500 -1875);
FORCEPROP 1 LAST CUSTOM_TXT_CDS <NAME_1>
J 0
(1500 -1750);
FORCEPROP 1 LAST CUSTOM_TXT_CDS <Q_NUMBER>
J 0
(3272 -1822);
DISPLAY 1.212766 (3272 -1822);
FORCEPROP 1 LAST CUSTOM_TXT_CDS <Q_PROJ>
J 0
(2293 -1823);
DISPLAY 1.212766 (2293 -1823);
FORCEPROP 1 LAST CUSTOM_TXT_CDS <Q_REV>
J 0
(4491 -1822);
DISPLAY 1.212766 (4491 -1822);
FORCEPROP 1 LAST CUSTOM_TXT_CDS <CON_PAGE_NUM> OF <CON_TOTAL_PAGES>
J 0
(4229 -1907);
DISPLAY 0.978723 (4229 -1907);
FORCEPROP 1 LAST Q_TITLE BMC HW STRAPS & MISC
J 0
(-4591 -1824);
DISPLAY 2.446809 (-4591 -1824);
PAINT GREEN (-4591 -1824);
FORCEPROP 1 LAST COMMENT_BODY TRUE
J 0
(4687 -1938);
DISPLAY 0.978723 (4687 -1938);
PAINT PEACH (4687 -1938);
DISPLAY INVISIBLE (4687 -1938);
FORCEPROP 2 LAST PAGE_BORDER TRUE
J 0
(-3215 3325);
DISPLAY 0.638298 (-3215 3325);
PAINT PINK (-3215 3325);
DISPLAY INVISIBLE (-3215 3325);
FORCEPROP 1 LAST CDS_LMAN_SYM_OUTLINE -9475,6775,100,-125
J 0
(4675 -1925);
DISPLAY 0.468085 (4675 -1925);
PAINT GREEN (4675 -1925);
DISPLAY INVISIBLE (4675 -1925);
FORCEPROP 2 LAST CDS_LIB pure_quanta
J 0
(4675 -1925);
DISPLAY INVISIBLE (4675 -1925);
FORCEPROP 2 LAST CDS_XR_PAGE_TITLE CR-27 : @SCM_LIB.SCM(SCH_1):PAGE27
J 0
(-3215 3325);
DISPLAY 0.638298 (-3215 3325);
PAINT PINK (-3215 3325);
DISPLAY INVISIBLE (-3215 3325);
FORCEADD DESIGN_NOTE..1
(1900 1350);
FORCEPROP 0 LAST L0 STRAP 8, ENABLE BOOT FROM UART5
J 0
(1725 1200);
DISPLAY 1.276596 (1725 1200);
PAINT GREEN (1725 1200);
FORCEPROP 0 LAST L3 0, JUST LEAVE THE PIN FLOATING
J 0
(1750 1075);
DISPLAY 1.021277 (1750 1075);
PAINT WHITE (1750 1075);
FORCEPROP 0 LAST STATUS 0
J 0
(4000 650);
DISPLAY 3.148936 (4000 650);
PAINT WHITE (4000 650);
FORCEPROP 0 LAST L4 1, PULL-HIGH THE PIN BY A RESISTOR OF VALUE 1K ~ 4.7K OHM
J 0
(1750 1000);
DISPLAY 1.021277 (1750 1000);
PAINT WHITE (1750 1000);
FORCEPROP 2 LAST CDS_LIB logical_power
J 0
(1900 1350);
DISPLAY INVISIBLE (1900 1350);
FORCEPROP 1 LAST COMMENT_BODY TRUE
J 0
(1925 1450);
DISPLAY 0.978723 (1925 1450);
PAINT PEACH (1925 1450);
DISPLAY INVISIBLE (1925 1450);
FORCEADD DNS..2
(-675 2500);
PAINT RED (-675 2500);
FORCEPROP 1 LAST COMMENT_BODY TRUE
R 1
J 0
(-600 2275);
DISPLAY 0.872340 (-600 2275);
PAINT PEACH (-600 2275);
DISPLAY INVISIBLE (-600 2275);
FORCEPROP 2 LAST CDS_LIB mstr_misc
J 0
(-675 2500);
DISPLAY INVISIBLE (-675 2500);
FORCEADD DNS..2
(-3325 -175);
PAINT RED (-3325 -175);
FORCEPROP 1 LAST COMMENT_BODY TRUE
R 1
J 0
(-3250 -400);
DISPLAY 0.872340 (-3250 -400);
PAINT GREEN (-3250 -400);
DISPLAY INVISIBLE (-3250 -400);
FORCEPROP 2 LAST CDS_LIB mstr_misc
J 0
(-3325 -175);
DISPLAY INVISIBLE (-3325 -175);
FORCEADD DNS..2
(-2775 -200);
PAINT RED (-2775 -200);
FORCEPROP 2 LAST CDS_LIB mstr_misc
J 0
(-2775 -200);
DISPLAY INVISIBLE (-2775 -200);
FORCEPROP 1 LAST COMMENT_BODY TRUE
R 1
J 0
(-2700 -425);
DISPLAY 0.872340 (-2700 -425);
PAINT GREEN (-2700 -425);
DISPLAY INVISIBLE (-2700 -425);
FORCEADD DESIGN_NOTE..1
(-1025 225);
FORCEPROP 0 LAST STATUS 0
J 0
(375 -525);
DISPLAY 3.148936 (375 -525);
PAINT WHITE (375 -525);
FORCEPROP 0 LAST L0 STRAP 31, ENABLE SECURE BOOT BY PIN STRAP
J 0
(-1200 75);
DISPLAY 1.276596 (-1200 75);
PAINT GREEN (-1200 75);
FORCEPROP 0 LAST L3 0, DISABLE SECURE BOOT,PULL DOWN(DEFAULT)
J 0
(-1175 -50);
DISPLAY 1.021277 (-1175 -50);
PAINT WHITE (-1175 -50);
FORCEPROP 0 LAST L4 1, ENABLE SCURE BOOT ,PULL-HIGH THE PIN
J 0
(-1175 -125);
DISPLAY 1.021277 (-1175 -125);
PAINT WHITE (-1175 -125);
FORCEPROP 2 LAST CDS_LIB logical_power
J 0
(-1025 225);
DISPLAY INVISIBLE (-1025 225);
FORCEPROP 1 LAST COMMENT_BODY TRUE
J 0
(-1000 325);
DISPLAY 0.978723 (-1000 325);
PAINT PEACH (-1000 325);
DISPLAY INVISIBLE (-1000 325);
FORCEADD DNS..2
(-2800 -1025);
PAINT RED (-2800 -1025);
FORCEPROP 1 LAST COMMENT_BODY TRUE
R 1
J 0
(-2725 -1250);
DISPLAY 0.872340 (-2725 -1250);
PAINT GREEN (-2725 -1250);
DISPLAY INVISIBLE (-2725 -1250);
FORCEPROP 2 LAST CDS_LIB mstr_misc
J 0
(-2800 -1025);
DISPLAY INVISIBLE (-2800 -1025);
FORCEADD DNS..2
(2650 -925);
PAINT RED (2650 -925);
FORCEPROP 1 LAST COMMENT_BODY TRUE
R 1
J 0
(2725 -1150);
DISPLAY 0.872340 (2725 -1150);
PAINT PEACH (2725 -1150);
DISPLAY INVISIBLE (2725 -1150);
FORCEPROP 2 LAST CDS_LIB mstr_misc
J 0
(2650 -925);
DISPLAY INVISIBLE (2650 -925);
FORCEADD DESIGN_NOTE..1
(3300 -1325);
FORCEPROP 0 LAST L4 1, LPC
J 0
(3125 -1625);
DISPLAY 1.021277 (3125 -1625);
PAINT WHITE (3125 -1625);
FORCEPROP 0 LAST L3 0, ESPI (DEFAULT)
J 0
(3125 -1550);
DISPLAY 1.021277 (3125 -1550);
PAINT WHITE (3125 -1550);
FORCEPROP 0 LAST L0 STRAP 6, SELECT LPC/ESPI
J 0
(3125 -1475);
DISPLAY 1.276596 (3125 -1475);
PAINT GREEN (3125 -1475);
FORCEPROP 2 LAST CDS_LIB logical_power
J 0
(3300 -1325);
DISPLAY INVISIBLE (3300 -1325);
FORCEPROP 1 LAST COMMENT_BODY TRUE
J 0
(3325 -1225);
DISPLAY 0.978723 (3325 -1225);
PAINT PEACH (3325 -1225);
DISPLAY INVISIBLE (3325 -1225);
FORCEADD DNS..2
(-675 2700);
PAINT RED (-675 2700);
FORCEPROP 1 LAST COMMENT_BODY TRUE
R 1
J 0
(-600 2475);
DISPLAY 0.872340 (-600 2475);
PAINT PEACH (-600 2475);
DISPLAY INVISIBLE (-600 2475);
FORCEPROP 2 LAST CDS_LIB mstr_misc
J 0
(-675 2700);
DISPLAY INVISIBLE (-675 2700);
FORCEADD DNS..2
(-3625 700);
PAINT RED (-3625 700);
FORCEPROP 1 LAST COMMENT_BODY TRUE
R 1
J 0
(-3550 475);
DISPLAY 0.872340 (-3550 475);
PAINT GREEN (-3550 475);
DISPLAY INVISIBLE (-3550 475);
FORCEPROP 2 LAST CDS_LIB mstr_misc
J 0
(-3625 700);
DISPLAY INVISIBLE (-3625 700);
FORCEADD DNS..2
(-3625 1300);
PAINT RED (-3625 1300);
FORCEPROP 2 LAST CDS_LIB mstr_misc
J 0
(-3625 1300);
DISPLAY INVISIBLE (-3625 1300);
FORCEPROP 1 LAST COMMENT_BODY TRUE
R 1
J 0
(-3550 1075);
DISPLAY 0.872340 (-3550 1075);
PAINT GREEN (-3550 1075);
DISPLAY INVISIBLE (-3550 1075);
FORCEADD DNS..2
(-3625 1375);
PAINT RED (-3625 1375);
FORCEPROP 2 LAST CDS_LIB mstr_misc
J 0
(-3625 1375);
DISPLAY INVISIBLE (-3625 1375);
FORCEPROP 1 LAST COMMENT_BODY TRUE
R 1
J 0
(-3550 1150);
DISPLAY 0.872340 (-3550 1150);
PAINT GREEN (-3550 1150);
DISPLAY INVISIBLE (-3550 1150);
FORCEADD DESIGN_NOTE..1
(-1525 -875);
FORCEPROP 0 LAST STATUS 0
J 0
(375 -725);
DISPLAY 3.148936 (375 -725);
PAINT WHITE (375 -725);
FORCEPROP 0 LAST L4 1,  PULL-HIGH THE PIN BY A RESISTOR OF VALUE 1K ~ 4.7K OHM
J 0
(-1675 -1225);
DISPLAY 1.021277 (-1675 -1225);
PAINT WHITE (-1675 -1225);
FORCEPROP 0 LAST L3 0,  JUST LEAVE THE PIN FLOATING OR PULL DOWN(DEFAULT)
J 0
(-1675 -1150);
DISPLAY 1.021277 (-1675 -1150);
PAINT WHITE (-1675 -1150);
FORCEPROP 0 LAST L0 STRAP 0, ENABLE LOW SECURE BOOT FUNCTION
J 0
(-1700 -1025);
DISPLAY 1.276596 (-1700 -1025);
PAINT GREEN (-1700 -1025);
FORCEPROP 2 LAST CDS_LIB logical_power
J 0
(-1525 -875);
DISPLAY INVISIBLE (-1525 -875);
FORCEPROP 1 LAST COMMENT_BODY TRUE
J 0
(-1500 -775);
DISPLAY 0.978723 (-1500 -775);
PAINT PEACH (-1500 -775);
DISPLAY INVISIBLE (-1500 -775);
FORCEADD DESIGN_NOTE..1
(2375 3625);
FORCEPROP 0 LAST L1 TO PCH GPIO AND BIOS CONTROL,
J 0
(2175 3475);
DISPLAY 1.276596 (2175 3475);
PAINT GREEN (2175 3475);
FORCEPROP 0 LAST L3 IF BMC DISABLE,
J 0
(2175 3375);
DISPLAY 1.340425 (2175 3375);
PAINT GREEN (2175 3375);
FORCEPROP 0 LAST L2 BIOS IS HIGH ACTIVITY
J 0
(2175 3275);
DISPLAY 1.276596 (2175 3275);
PAINT GREEN (2175 3275);
FORCEPROP 1 LAST COMMENT_BODY TRUE
J 0
(2400 3725);
DISPLAY 0.978723 (2400 3725);
PAINT PEACH (2400 3725);
DISPLAY INVISIBLE (2400 3725);
FORCEPROP 2 LAST CDS_LIB logical_power
J 0
(2375 3625);
PAINT MONO (2375 3625);
DISPLAY INVISIBLE (2375 3625);
FORCEADD DESIGN_NOTE..1
(2175 4450);
FORCEPROP 1 LAST COMMENT_BODY TRUE
J 0
(2200 4550);
DISPLAY 0.978723 (2200 4550);
PAINT PEACH (2200 4550);
DISPLAY INVISIBLE (2200 4550);
FORCEPROP 2 LAST CDS_LIB logical_power
J 0
(2175 4450);
PAINT MONO (2175 4450);
DISPLAY INVISIBLE (2175 4450);
FORCEADD DNS..2
(2500 475);
PAINT RED (2500 475);
FORCEPROP 1 LAST COMMENT_BODY TRUE
R 1
J 0
(2575 250);
DISPLAY 0.872340 (2575 250);
PAINT PEACH (2575 250);
DISPLAY INVISIBLE (2575 250);
FORCEPROP 2 LAST CDS_LIB mstr_misc
J 0
(2500 475);
DISPLAY INVISIBLE (2500 475);
WIRE 16 -1 (-4075 4275)(-4075 4175);
WIRE 16 -1 (-4075 1450)(-4075 1350);
WIRE 16 -1 (-3325 -50)(-3325 125);
WIRE 16 -1 (-2825 -50)(-2825 125);
WIRE 16 -1 (2375 -150)(2375 -175);
WIRE 16 -1 (-1075 2925)(-1075 2725);
WIRE 16 -1 (2100 700)(2100 500);
WIRE 16 -1 (-1075 4300)(-1075 4200);
WIRE 16 -1 (2750 2725)(2750 2825);
WIRE 16 -1 (-2825 -1250)(-2825 -1100);
WIRE 16 -1 (-3325 -1250)(-3325 -1075);
WIRE 16 -1 (2650 -1000)(2650 -1075);
WIRE 16 -1 (-1075 2375)(-1075 2525);
WIRE 16 -1 (-4075 1675)(-3725 1675);
WIRE 16 -1 (-4075 1775)(-4075 1675);
WIRE 16 -1 (-3725 1775)(-4075 1775);
WIRE 16 -1 (-4075 1775)(-4075 1875);
WIRE 16 -1 (-4075 1875)(-3725 1875);
WIRE 16 -1 (-4075 1975)(-4075 1875);
WIRE 16 -1 (-3725 1975)(-4075 1975);
WIRE 16 -1 (-4075 2075)(-4075 1975);
WIRE 16 -1 (-3725 2075)(-4075 2075);
WIRE 16 -1 (-4075 2175)(-4075 2075);
WIRE 16 -1 (-3725 2175)(-4075 2175);
WIRE 16 -1 (-4075 2275)(-4075 2175);
WIRE 16 -1 (-3725 2275)(-4075 2275);
WIRE 16 -1 (-4075 2375)(-4075 2275);
WIRE 16 -1 (-3725 2375)(-4075 2375);
WIRE 16 -1 (-4075 2475)(-4075 2375);
WIRE 16 -1 (-3725 2475)(-4075 2475);
WIRE 16 -1 (-4075 2475)(-4075 2575);
WIRE 16 -1 (-3725 2575)(-4075 2575);
WIRE 16 -1 (-4075 2675)(-4075 2575);
WIRE 16 -1 (-3725 2675)(-4075 2675);
WIRE 16 -1 (-4075 2775)(-4075 2675);
WIRE 16 -1 (-3725 2775)(-4075 2775);
WIRE 16 -1 (-4075 2875)(-4075 2775);
WIRE 16 -1 (-3725 2875)(-4075 2875);
WIRE 16 -1 (-4075 2875)(-4075 2975);
WIRE 16 -1 (-3725 2975)(-4075 2975);
WIRE 16 -1 (-4075 3075)(-4075 2975);
WIRE 16 -1 (-3725 3075)(-4075 3075);
WIRE 16 -1 (-4075 3175)(-4075 3075);
WIRE 16 -1 (-3725 3175)(-4075 3175);
WIRE 16 -1 (-4075 3275)(-4075 3175);
WIRE 16 -1 (-3725 3275)(-4075 3275);
WIRE 16 -1 (-4075 3275)(-4075 3375);
WIRE 16 -1 (-3725 3375)(-4075 3375);
WIRE 16 -1 (-4075 3475)(-4075 3375);
WIRE 16 -1 (-3725 3475)(-4075 3475);
WIRE 16 -1 (-4075 3575)(-4075 3475);
WIRE 16 -1 (-3725 3575)(-4075 3575);
WIRE 16 -1 (-4075 3675)(-4075 3575);
WIRE 16 -1 (-3725 3675)(-4075 3675);
WIRE 16 -1 (-4075 3675)(-4075 3775);
WIRE 16 -1 (-3725 3775)(-4075 3775);
WIRE 16 -1 (-4075 3875)(-4075 3775);
WIRE 16 -1 (-3725 3875)(-4075 3875);
WIRE 16 -1 (-4075 3975)(-4075 3875);
WIRE 16 -1 (-3725 3975)(-4075 3975);
WIRE 16 -1 (-4075 4075)(-4075 3975);
WIRE 16 -1 (-3725 4075)(-4075 4075);
WIRE 16 -1 (-4075 4075)(-4075 4175);
WIRE 16 -1 (-3725 4175)(-4075 4175);
WIRE 16 -1 (-1925 3575)(-3525 3575);
FORCEPROP 2 LAST SIG_NAME SMB_BMC_MM4_SCL
J 0
(-3075 3585);
DISPLAY 0.808511 (-3075 3585);
WIRE 16 -1 (-1925 3875)(-3525 3875);
FORCEPROP 2 LAST SIG_NAME SMB_BMC_MM2_SDA
J 0
(-3075 3885);
DISPLAY 0.808511 (-3075 3885);
WIRE 16 -1 (-1925 3975)(-3525 3975);
FORCEPROP 2 LAST SIG_NAME SMB_BMC_MM2_SCL
J 0
(-3075 3985);
DISPLAY 0.808511 (-3075 3985);
WIRE 16 -1 (-1925 4175)(-3525 4175);
FORCEPROP 2 LAST SIG_NAME SMB_BMC_MM1_SCL
J 0
(-3075 4185);
DISPLAY 0.808511 (-3075 4185);
WIRE 16 -1 (-1925 4075)(-3525 4075);
FORCEPROP 2 LAST SIG_NAME SMB_BMC_MM1_SDA
J 0
(-3075 4085);
DISPLAY 0.808511 (-3075 4085);
WIRE 16 -1 (-1925 3775)(-3525 3775);
FORCEPROP 2 LAST SIG_NAME SMB_BMC_MM3_SCL
J 0
(-3075 3785);
DISPLAY 0.808511 (-3075 3785);
WIRE 16 -1 (-1925 3675)(-3525 3675);
FORCEPROP 2 LAST SIG_NAME SMB_BMC_MM3_SDA
J 0
(-3075 3685);
DISPLAY 0.808511 (-3075 3685);
WIRE 16 3135 (-3675 3450)(-3575 3450);
WIRE 16 3135 (-3675 3600)(-3675 3450);
WIRE 16 3135 (-3575 3450)(-3575 3600);
WIRE 16 3135 (-3575 3600)(-3675 3600);
WIRE 16 -1 (-1925 3475)(-3525 3475);
FORCEPROP 2 LAST SIG_NAME SMB_BMC_MM4_SDA
J 0
(-3075 3485);
DISPLAY 0.808511 (-3075 3485);
WIRE 16 -1 (-1925 3375)(-3525 3375);
FORCEPROP 2 LAST SIG_NAME SMB_BMC_MM5_R_SCL
J 0
(-3075 3385);
DISPLAY 0.808511 (-3075 3385);
WIRE 16 -1 (-1925 3275)(-3525 3275);
FORCEPROP 2 LAST SIG_NAME SMB_BMC_MM5_R_SDA
J 0
(-3075 3285);
DISPLAY 0.808511 (-3075 3285);
WIRE 16 -1 (-1925 3175)(-3525 3175);
FORCEPROP 2 LAST SIG_NAME SMB_BMC_MM6_SCL
J 0
(-3075 3185);
DISPLAY 0.808511 (-3075 3185);
WIRE 16 -1 (-1925 3075)(-3525 3075);
FORCEPROP 2 LAST SIG_NAME SMB_BMC_MM6_SDA
J 0
(-3075 3085);
DISPLAY 0.808511 (-3075 3085);
WIRE 16 -1 (-1925 2975)(-3525 2975);
FORCEPROP 2 LAST SIG_NAME SMB_BMC_MM7_R_SCL
J 0
(-3075 2985);
DISPLAY 0.808511 (-3075 2985);
WIRE 16 -1 (-1925 2875)(-3525 2875);
FORCEPROP 2 LAST SIG_NAME SMB_BMC_MM7_R_SDA
J 0
(-3075 2885);
DISPLAY 0.808511 (-3075 2885);
WIRE 16 -1 (-3525 2575)(-1925 2575);
FORCEPROP 2 LAST SIG_NAME SMB_BMC_MM9_SCL
J 0
(-3075 2585);
DISPLAY 0.808511 (-3075 2585);
WIRE 16 -1 (-3525 2175)(-1925 2175);
FORCEPROP 2 LAST SIG_NAME SMB_BMC_MM12_SCL
J 0
(-3075 2185);
DISPLAY 0.808511 (-3075 2185);
WIRE 16 -1 (-3525 2075)(-1925 2075);
FORCEPROP 2 LAST SIG_NAME SMB_BMC_MM12_SDA
J 0
(-3075 2085);
DISPLAY 0.808511 (-3075 2085);
WIRE 16 -1 (-1925 1675)(-3525 1675);
FORCEPROP 2 LAST SIG_NAME SMB_BMC_MM16_SDA
J 0
(-3075 1685);
DISPLAY 0.808511 (-3075 1685);
WIRE 16 3135 (-3575 4050)(-3575 4200);
WIRE 16 3135 (-3675 4050)(-3575 4050);
WIRE 16 3135 (-3575 4200)(-3675 4200);
WIRE 16 3135 (-3675 4200)(-3675 4050);
WIRE 16 3135 (-3575 3050)(-3575 3200);
WIRE 16 3135 (-3675 3050)(-3575 3050);
WIRE 16 3135 (-3575 3200)(-3675 3200);
WIRE 16 3135 (-3675 3200)(-3675 3050);
WIRE 16 -1 (-1925 2775)(-3525 2775);
FORCEPROP 2 LAST SIG_NAME SMB_BMC_MM8_SCL
J 0
(-3075 2785);
DISPLAY 0.808511 (-3075 2785);
WIRE 16 -1 (-3525 2275)(-1925 2275);
FORCEPROP 2 LAST SIG_NAME SMB_BMC_MM10_SDA
J 0
(-3075 2285);
DISPLAY 0.808511 (-3075 2285);
WIRE 16 -1 (-3525 975)(-2575 975);
FORCEPROP 2 LAST SIG_NAME SMB_BMC_ALERT10_N
J 0
(-3225 985);
DISPLAY 0.808511 (-3225 985);
WIRE 16 -1 (-2575 1350)(-3525 1350);
FORCEPROP 2 LAST SIG_NAME FM_ME_BT_DONE
J 0
(-3225 1360);
DISPLAY 0.808511 (-3225 1360);
WIRE 16 -1 (-3525 1975)(-1925 1975);
FORCEPROP 2 LAST SIG_NAME SMB_BMC_MM15_SCL
J 0
(-3075 1985);
DISPLAY 0.808511 (-3075 1985);
WIRE 16 -1 (-1925 1875)(-3525 1875);
FORCEPROP 2 LAST SIG_NAME SMB_BMC_MM15_SDA
J 0
(-3075 1885);
DISPLAY 0.808511 (-3075 1885);
WIRE 16 -1 (-3525 1775)(-1925 1775);
FORCEPROP 2 LAST SIG_NAME SMB_BMC_MM16_SCL
J 0
(-3075 1785);
DISPLAY 0.808511 (-3075 1785);
WIRE 16 -1 (-2575 1050)(-3525 1050);
FORCEPROP 2 LAST SIG_NAME SMB_BMC_ALERT9_N
J 0
(-3225 1060);
DISPLAY 0.808511 (-3225 1060);
WIRE 16 -1 (-2575 1125)(-3525 1125);
FORCEPROP 2 LAST SIG_NAME SMB_BMC_ALERT4_N
J 0
(-3225 1135);
DISPLAY 0.808511 (-3225 1135);
WIRE 16 -1 (-3525 1200)(-2575 1200);
FORCEPROP 2 LAST SIG_NAME SMB_BMC_ALERT3_N
J 0
(-3225 1210);
DISPLAY 0.808511 (-3225 1210);
WIRE 16 -1 (-3525 1275)(-2575 1275);
FORCEPROP 2 LAST SIG_NAME VOL_SEN_ALERT_R
J 0
(-3225 1285);
DISPLAY 0.808511 (-3225 1285);
WIRE 16 -1 (-2575 825)(-3525 825);
FORCEPROP 2 LAST SIG_NAME SMB_BMC_ALERT12_N
J 0
(-3225 835);
DISPLAY 0.808511 (-3225 835);
WIRE 16 -1 (-3525 2475)(-1925 2475);
FORCEPROP 2 LAST SIG_NAME SMB_BMC_MM9_SDA
J 0
(-3075 2485);
DISPLAY 0.808511 (-3075 2485);
WIRE 16 3135 (-3575 2025)(-3575 2600);
WIRE 16 3135 (-3675 2025)(-3575 2025);
WIRE 16 3135 (-3575 2600)(-3675 2600);
WIRE 16 3135 (-3675 2600)(-3675 2025);
WIRE 16 -1 (-2575 675)(-3525 675);
FORCEPROP 2 LAST SIG_NAME FM_BMC_EN_DET_R
J 0
(-3225 685);
DISPLAY 0.808511 (-3225 685);
WIRE 16 -1 (-3325 -250)(-3325 -500);
WIRE 16 -1 (-125 -500)(-3325 -500);
FORCEPROP 0 LAST SIG_NAME SPI_BMC_BOOT_MOSI
J 0
(-910 -490);
DISPLAY 0.808511 (-910 -490);
WIRE 16 -1 (-3325 -875)(-3325 -500);
WIRE 16 -1 (-2825 -650)(-2825 -900);
WIRE 16 -1 (-2825 -250)(-2825 -650);
WIRE 16 -1 (-150 -650)(-2825 -650);
FORCEPROP 0 LAST SIG_NAME SPI_BMC_BOOT_MISO
J 0
(-910 -640);
DISPLAY 0.808511 (-910 -640);
WIRE 16 -1 (-3525 2375)(-1925 2375);
FORCEPROP 2 LAST SIG_NAME SMB_BMC_MM10_SCL
J 0
(-3075 2385);
DISPLAY 0.808511 (-3075 2385);
WIRE 16 -1 (-1925 2675)(-3525 2675);
FORCEPROP 2 LAST SIG_NAME SMB_BMC_MM8_SDA
J 0
(-3075 2685);
DISPLAY 0.808511 (-3075 2685);
WIRE 16 -1 (3800 -925)(3800 -1100);
WIRE 16 -1 (4400 -1100)(3800 -1100);
FORCEPROP 2 LAST SIG_NAME SPI_BMC_TPM_MOSI
J 0
(3815 -1090);
DISPLAY 0.808511 (3815 -1090);
WIRE 16 -1 (-575 2525)(-225 2525);
WIRE 16 -1 (-225 2725)(-575 2725);
WIRE 16 -1 (-225 2525)(-225 2725);
WIRE 16 -1 (750 2725)(-225 2725);
FORCEPROP 2 LAST SIG_NAME UART_BMC_5_TXD_R
J 2
(515 2735);
DISPLAY 0.808511 (515 2735);
WIRE 16 -1 (1075 3900)(-525 3900);
FORCEPROP 2 LAST SIG_NAME SMB_BMC_MM14_SDA
J 0
(-75 3910);
DISPLAY 0.808511 (-75 3910);
WIRE 16 -1 (1075 4000)(-525 4000);
FORCEPROP 2 LAST SIG_NAME SMB_BMC_MM14_SCL
J 0
(-75 4010);
DISPLAY 0.808511 (-75 4010);
WIRE 16 3135 (1975 4125)(3850 4125);
WIRE 16 3135 (1975 4375)(1975 4125);
WIRE 16 3135 (3850 4125)(3850 4375);
WIRE 16 3135 (3850 4375)(1975 4375);
WIRE 16 3135 (2025 4250)(3700 4250);
WIRE 16 3135 (2850 4350)(2850 4150);
WIRE 16 3135 (3425 4075)(3425 3775);
WIRE 16 3135 (3375 4350)(3375 4150);
WIRE 16 3135 (2925 4075)(2925 3775);
WIRE 16 3135 (2625 4350)(2625 4150);
WIRE 16 -1 (2750 2250)(2750 2425);
WIRE 16 -1 (3675 2425)(2750 2425);
FORCEPROP 2 LAST SIG_NAME FM_BMC_ONCTL_R_N
J 2
(3625 2435);
DISPLAY 0.808511 (3625 2435);
WIRE 16 -1 (2750 2525)(2750 2425);
WIRE 16 -1 (2850 2250)(2850 2300);
WIRE 16 -1 (3675 2300)(2850 2300);
FORCEPROP 0 LAST SIG_NAME UART_BMC_5_TXD_R
J 2
(3625 2310);
DISPLAY 0.808511 (3625 2310);
WIRE 16 -1 (1075 4100)(-525 4100);
FORCEPROP 2 LAST SIG_NAME SMB_BMC_MM13_SDA
J 0
(-75 4110);
DISPLAY 0.808511 (-75 4110);
WIRE 16 -1 (1075 4200)(-525 4200);
FORCEPROP 2 LAST SIG_NAME SMB_BMC_MM13_SCL
J 0
(-75 4210);
DISPLAY 0.808511 (-75 4210);
WIRE 16 -1 (-2575 600)(-3525 600);
FORCEPROP 2 LAST SIG_NAME SMB_BMC_ALERT15_N
J 0
(-3225 610);
DISPLAY 0.808511 (-3225 610);
WIRE 16 -1 (-2575 525)(-3525 525);
FORCEPROP 2 LAST SIG_NAME SMB_BMC_ALERT16_N
J 0
(-3225 535);
DISPLAY 0.808511 (-3225 535);
WIRE 16 -1 (2375 -425)(2375 -375);
WIRE 16 -1 (2900 -425)(2375 -425);
FORCEPROP 2 LAST SIG_NAME Q7_D
J 0
(2840 -415);
DISPLAY 0.851064 (2840 -415);
WIRE 16 -1 (2650 -675)(2325 -675);
FORCEPROP 2 LAST SIG_NAME LPC_ESPI_SEL_R1
J 0
(2290 -665);
DISPLAY 0.808511 (2290 -665);
WIRE 16 -1 (2650 -675)(2650 -800);
WIRE 16 -1 (2900 -675)(2650 -675);
WIRE 16 -1 (2125 -675)(1575 -675);
FORCEPROP 2 LAST SIG_NAME LPC_ESPI_SEL
J 0
(1590 -665);
DISPLAY 0.808511 (1590 -665);
WIRE 16 273 (3625 -1125)(3475 -1150);
WIRE 16 273 (3575 -1225)(3625 -1125);
WIRE 16 273 (3400 -1250)(3625 -1125);
WIRE 16 -1 (3925 500)(2600 500);
FORCEPROP 2 LAST SIG_NAME SPI_BMC_BOOT_CLK
J 2
(3825 510);
DISPLAY 0.808511 (3825 510);
WIRE 16 -1 (2800 2000)(2800 2050);
WIRE 16 -1 (1975 2000)(2800 2000);
FORCEPROP 0 LAST SIG_NAME FM_BMC_DISABLE
J 0
(2040 2010);
DISPLAY 0.808511 (2040 2010);
WIRE 16 3135 (2000 3875)(3825 3875);
WIRE 16 3135 (2000 4000)(3825 4000);
WIRE 16 3135 (1975 4100)(1975 3750);
WIRE 16 3135 (3850 3750)(1975 3750);
WIRE 16 3135 (1975 4100)(3850 4100);
WIRE 16 3135 (3850 4100)(3850 3750);
WIRE 16 -1 (-3725 525)(-4075 525);
WIRE 16 -1 (-4075 525)(-4075 600);
WIRE 16 -1 (-3725 600)(-4075 600);
WIRE 16 -1 (-4075 600)(-4075 675);
WIRE 16 -1 (-3725 675)(-4075 675);
WIRE 16 -1 (-4075 675)(-4075 825);
WIRE 16 -1 (-3725 825)(-4075 825);
WIRE 16 -1 (-4075 825)(-4075 975);
WIRE 16 -1 (-3725 975)(-4075 975);
WIRE 16 -1 (-4075 1050)(-4075 975);
WIRE 16 -1 (-3725 1050)(-4075 1050);
WIRE 16 -1 (-4075 1050)(-4075 1125);
WIRE 16 -1 (-3725 1125)(-4075 1125);
WIRE 16 -1 (-4075 1125)(-4075 1200);
WIRE 16 -1 (-3725 1200)(-4075 1200);
WIRE 16 -1 (-4075 1200)(-4075 1275);
WIRE 16 -1 (-3725 1275)(-4075 1275);
WIRE 16 -1 (-4075 1275)(-4075 1350);
WIRE 16 -1 (-3725 1350)(-4075 1350);
WIRE 16 -1 (-1075 2525)(-775 2525);
WIRE 16 -1 (-1075 2725)(-775 2725);
WIRE 16 -1 (-725 3900)(-1075 3900);
WIRE 16 -1 (-1075 4000)(-1075 3900);
WIRE 16 -1 (-725 4000)(-1075 4000);
WIRE 16 -1 (-1075 4100)(-1075 4000);
WIRE 16 -1 (-725 4100)(-1075 4100);
WIRE 16 -1 (-1075 4100)(-1075 4200);
WIRE 16 -1 (-725 4200)(-1075 4200);
WIRE 16 -1 (2100 500)(2400 500);
DOT 1 (-4075 4175);
DOT 1 (-4075 4075);
DOT 1 (-4075 3475);
DOT 1 (-4075 2575);
DOT 1 (-4075 3175);
DOT 1 (-4075 3075);
DOT 1 (-4075 3375);
DOT 1 (-4075 2475);
DOT 1 (-4075 2375);
DOT 1 (-4075 2275);
DOT 1 (-4075 2175);
DOT 1 (-4075 3275);
DOT 1 (-4075 2875);
DOT 1 (-4075 3875);
DOT 1 (-4075 2775);
DOT 1 (-4075 2675);
DOT 1 (-4075 3675);
DOT 1 (-4075 3775);
DOT 1 (-4075 1975);
DOT 1 (-4075 1200);
DOT 1 (-4075 975);
DOT 1 (-2825 -650);
DOT 1 (-3325 -500);
DOT 1 (2650 -675);
DOT 1 (-225 2725);
DOT 1 (-1075 4000);
DOT 1 (-1075 4100);
DOT 1 (-4075 3975);
DOT 1 (2750 2425);
DOT 1 (-4075 2975);
DOT 1 (-4075 1875);
DOT 1 (-4075 1775);
DOT 1 (-1075 4200);
DOT 1 (-4075 1350);
DOT 1 (-4075 1275);
DOT 1 (-4075 1125);
DOT 1 (-4075 1050);
DOT 1 (-4075 825);
DOT 1 (-4075 600);
DOT 1 (-4075 675);
DOT 1 (-4075 2075);
DOT 1 (3625 -1125);
DOT 1 (-4075 3575);
FORCENOTE
CHANGE TO 10KOHM_20221222
(-3875 2625) 0;
DISPLAY LEFT (-3875 2625);
DISPLAY 0.638298 (-3875 2625);
PAINT WHITE (-3875 2625);
FORCENOTE
DISABLE CPU BOOT
(2025 4175) 0;
DISPLAY LEFT (2025 4175);
DISPLAY 0.638298 (2025 4175);
FORCENOTE
NUMBER
(2650 4275) 0;
DISPLAY LEFT (2650 4275);
DISPLAY 0.638298 (2650 4275);
FORCENOTE
SIGNAL NAME
(2875 4300) 0;
DISPLAY LEFT (2875 4300);
DISPLAY 0.638298 (2875 4300);
FORCENOTE
BALL NAME: FWSPICS0#
(2475 4400) 0;
DISPLAY LEFT (2475 4400);
DISPLAY 0.680851 (2475 4400);
PAINT YELLOW (2475 4400);
FORCENOTE
BIT 0 (DEDICATED STRAP PIN)
(2475 4450) 0;
DISPLAY LEFT (2475 4450);
DISPLAY 0.680851 (2475 4450);
PAINT YELLOW (2475 4450);
FORCENOTE
DISABLE BMC
(2975 3800) 0;
DISPLAY LEFT (2975 3800);
DISPLAY 0.808511 (2975 3800);
FORCENOTE
0(DEFAULT)
(2400 3925) 0;
DISPLAY LEFT (2400 3925);
DISPLAY 0.638298 (2400 3925);
FORCENOTE
STRAP VALUE = INVERSE OF INPUT
(2000 4050) 0;
DISPLAY LEFT (2000 4050);
DISPLAY 0.638298 (2000 4050);
FORCENOTE
DESCRIPTION
(3025 4050) 0;
DISPLAY LEFT (3025 4050);
DISPLAY 0.638298 (3025 4050);
FORCENOTE
ENABLE  BMC
(2975 3925) 0;
DISPLAY LEFT (2975 3925);
DISPLAY 0.808511 (2975 3925);
FORCENOTE
PU
(3600 3925) 0;
DISPLAY LEFT (3600 3925);
DISPLAY 0.808511 (3600 3925);
FORCENOTE
1
(2400 3800) 0;
DISPLAY LEFT (2400 3800);
DISPLAY 0.638298 (2400 3800);
FORCENOTE
PU(P3V3_RGM)
(3425 4175) 0;
DISPLAY LEFT (3425 4175);
DISPLAY 0.638298 (3425 4175);
FORCENOTE
INPUT LEVEL
(3475 4050) 0;
DISPLAY LEFT (3475 4050);
DISPLAY 0.638298 (3475 4050);
FORCENOTE
PD
(3600 3800) 0;
DISPLAY LEFT (3600 3800);
DISPLAY 0.808511 (3600 3800);
FORCENOTE
INTERNAL
(3425 4325) 0;
DISPLAY LEFT (3425 4325);
DISPLAY 0.638298 (3425 4325);
FORCENOTE
PU/PD
(3425 4275) 0;
DISPLAY LEFT (3425 4275);
DISPLAY 0.638298 (3425 4275);
FORCENOTE
STRAP NET NAME
(2025 4300) 0;
DISPLAY LEFT (2025 4300);
DISPLAY 0.638298 (2025 4300);
FORCENOTE
C8
(2650 4175) 0;
DISPLAY LEFT (2650 4175);
DISPLAY 0.638298 (2650 4175);
FORCENOTE
UART_BMC_5_TXD_R
(2875 4175) 0;
DISPLAY LEFT (2875 4175);
DISPLAY 0.638298 (2875 4175);
FORCENOTE
BALL
(2650 4325) 0;
DISPLAY LEFT (2650 4325);
DISPLAY 0.638298 (2650 4325);
FORCENOTE
STRAP VALUE=
(2000 3925) 0;
DISPLAY LEFT (2000 3925);
DISPLAY 0.638298 (2000 3925);
FORCENOTE
STRAP VALUE=
(2000 3800) 0;
DISPLAY LEFT (2000 3800);
DISPLAY 0.638298 (2000 3800);
FORCENOTE
CHANGE TO 10KOHM_20221222
(-3875 3225) 0;
DISPLAY LEFT (-3875 3225);
DISPLAY 0.638298 (-3875 3225);
PAINT WHITE (-3875 3225);
FORCENOTE
CHANGE TO 500OHM_20221206
(-3850 3525) 0;
DISPLAY LEFT (-3850 3525);
DISPLAY 0.638298 (-3850 3525);
PAINT WHITE (-3850 3525);
FORCENOTE
CHANGE TO 400OHM_20230421
(-3850 3625) 0;
DISPLAY LEFT (-3850 3625);
DISPLAY 0.638298 (-3850 3625);
PAINT WHITE (-3850 3625);
FORCENOTE
CHANGE TO CS21802FB02 1.8K_20230314
(-3850 4225) 0;
DISPLAY LEFT (-3850 4225);
DISPLAY 0.638298 (-3850 4225);
PAINT WHITE (-3850 4225);
QUIT
